G04*
G04 #@! TF.GenerationSoftware,Altium Limited,Altium Designer,23.7.1 (13)*
G04*
G04 Layer_Physical_Order=6*
G04 Layer_Color=16711680*
%FSLAX25Y25*%
%MOIN*%
G70*
G04*
G04 #@! TF.SameCoordinates,AF00DCEB-AC48-4C7C-91EA-99F42E284231*
G04*
G04*
G04 #@! TF.FilePolarity,Positive*
G04*
G01*
G75*
%ADD11C,0.02000*%
%ADD16C,0.00500*%
%ADD18C,0.01000*%
%ADD19C,0.00600*%
%ADD25C,0.00800*%
%ADD42R,0.01772X0.01772*%
%ADD43R,0.04331X0.04134*%
%ADD46R,0.04134X0.04331*%
%ADD52R,0.01457X0.00945*%
%ADD53R,0.01575X0.04252*%
%ADD60R,0.01968X0.01772*%
%ADD64R,0.02165X0.02165*%
%ADD68R,0.01772X0.01968*%
%ADD69R,0.02165X0.02165*%
%ADD86R,0.02816X0.02648*%
%ADD87R,0.02016X0.02288*%
%ADD88R,0.02911X0.02648*%
%ADD89R,0.02756X0.02756*%
%ADD106R,0.02559X0.02362*%
%ADD113R,0.02648X0.02911*%
%ADD119R,0.02362X0.02559*%
%ADD120R,0.02288X0.02016*%
%ADD124R,0.02648X0.02816*%
%ADD141R,0.02800X0.16500*%
%ADD142R,0.02800X0.12600*%
%ADD210C,0.11800*%
%ADD211R,0.10827X0.10827*%
%ADD212C,0.10827*%
%ADD217C,0.06299*%
%ADD218C,0.04331*%
%ADD231C,0.03000*%
%ADD236C,0.06102*%
%ADD237R,0.06102X0.06102*%
%ADD238R,0.06299X0.06299*%
%ADD239C,0.25000*%
%ADD240O,0.04921X0.04134*%
%ADD241O,0.07480X0.04724*%
%ADD242C,0.25591*%
%ADD243C,0.02166*%
%ADD244C,0.10000*%
%ADD245C,0.24000*%
%ADD246C,0.08661*%
%ADD247R,0.07874X0.07874*%
%ADD248R,0.05906X0.05906*%
%ADD249C,0.05906*%
%ADD250C,0.01600*%
%ADD251C,0.20000*%
%ADD252C,0.00500*%
G04:AMPARAMS|DCode=253|XSize=25.98mil|YSize=12.6mil|CornerRadius=1.58mil|HoleSize=0mil|Usage=FLASHONLY|Rotation=0.000|XOffset=0mil|YOffset=0mil|HoleType=Round|Shape=RoundedRectangle|*
%AMROUNDEDRECTD253*
21,1,0.02598,0.00945,0,0,0.0*
21,1,0.02284,0.01260,0,0,0.0*
1,1,0.00315,0.01142,-0.00472*
1,1,0.00315,-0.01142,-0.00472*
1,1,0.00315,-0.01142,0.00472*
1,1,0.00315,0.01142,0.00472*
%
%ADD253ROUNDEDRECTD253*%
%ADD254R,0.02559X0.02559*%
%ADD255R,0.02559X0.02559*%
%ADD256R,0.02559X0.02756*%
%ADD257R,0.02835X0.03937*%
%ADD258R,0.02165X0.01968*%
%ADD259R,0.01968X0.02362*%
%ADD260R,0.02712X0.02648*%
%ADD261R,0.02953X0.02756*%
%ADD262R,0.02362X0.01968*%
%ADD263R,0.01772X0.01772*%
%ADD264R,0.03347X0.02953*%
%ADD265R,0.03150X0.03740*%
%ADD266R,0.03937X0.04921*%
%ADD267R,0.04921X0.03937*%
%ADD268R,0.02029X0.01860*%
%ADD269R,0.02205X0.02047*%
%ADD270R,0.02520X0.02677*%
%ADD271R,0.02756X0.02756*%
%ADD272R,0.02677X0.02520*%
%ADD273R,0.02362X0.03150*%
%ADD274C,0.01200*%
%ADD275R,0.07382X0.06791*%
G36*
X109849Y-45276D02*
X104331D01*
Y-44488D01*
X90453D01*
Y-57874D01*
X82284D01*
Y-40945D01*
X84449D01*
Y-33858D01*
X85433Y-33858D01*
X109849D01*
Y-45276D01*
D02*
G37*
G36*
X335433Y-64446D02*
X290551D01*
Y-133858D01*
X266142D01*
Y-48425D01*
X300394D01*
Y-27953D01*
X335433D01*
Y-64446D01*
D02*
G37*
G36*
X512598Y-155462D02*
X512548Y-155512D01*
X484646D01*
Y-136221D01*
X492913D01*
Y-59842D01*
X451968D01*
Y-34252D01*
X512598D01*
Y-155462D01*
D02*
G37*
G36*
X375907Y-112979D02*
X398425D01*
Y-129921D01*
X398902Y-130398D01*
Y-131905D01*
X400410D01*
X407257Y-138753D01*
Y-152706D01*
X407058Y-153185D01*
Y-153901D01*
X407257Y-154381D01*
Y-170252D01*
X395225Y-182283D01*
X392612D01*
X392545Y-182183D01*
Y-181355D01*
X392228Y-180589D01*
X391642Y-180003D01*
X390876Y-179686D01*
X390048D01*
X389282Y-180003D01*
X388696Y-180589D01*
X388379Y-181355D01*
Y-182183D01*
X388312Y-182283D01*
X382791D01*
X382248Y-182058D01*
X381532D01*
X380988Y-182283D01*
X380523D01*
X380516Y-182277D01*
X379854Y-182003D01*
X379138D01*
X378477Y-182277D01*
X377970Y-182783D01*
X377696Y-183445D01*
Y-184161D01*
X377970Y-184822D01*
X378477Y-185329D01*
X379138Y-185603D01*
X379429D01*
Y-195179D01*
X379344Y-195214D01*
X378837Y-195720D01*
X378563Y-196382D01*
Y-197098D01*
X378837Y-197760D01*
X379344Y-198266D01*
X379429Y-198301D01*
Y-202804D01*
X379318Y-202915D01*
X379009Y-203378D01*
X378900Y-203924D01*
X378900Y-203924D01*
Y-225603D01*
X378900Y-225603D01*
X379009Y-226150D01*
X379318Y-226613D01*
X379429Y-226723D01*
Y-230413D01*
X361780D01*
Y-213333D01*
X358792D01*
X358500Y-213041D01*
X357838Y-212767D01*
X357122D01*
X356461Y-213041D01*
X356169Y-213333D01*
X355521D01*
Y-173140D01*
X393307D01*
Y-170721D01*
X393343Y-170698D01*
X394059D01*
X394720Y-170424D01*
X395227Y-169917D01*
X395501Y-169256D01*
Y-168540D01*
X395227Y-167878D01*
X394720Y-167372D01*
X394059Y-167098D01*
X393343D01*
X393307Y-167074D01*
Y-132960D01*
X386998D01*
Y-126772D01*
X383604D01*
X383441Y-126704D01*
X382724D01*
X382561Y-126772D01*
X375907D01*
Y-150787D01*
X363715D01*
Y-157258D01*
X369756D01*
Y-166177D01*
X350864D01*
Y-112964D01*
X375907D01*
Y-112979D01*
D02*
G37*
G36*
X546850Y-251181D02*
X562942D01*
X563283Y-251522D01*
X563746Y-251831D01*
X564292Y-251940D01*
X564292Y-251940D01*
X580590D01*
X580590Y-251940D01*
X580716Y-251915D01*
X581102Y-252232D01*
Y-264612D01*
X575591D01*
X575005Y-264729D01*
X574509Y-265060D01*
X574170Y-265400D01*
X554572D01*
X553986Y-265516D01*
X553490Y-265848D01*
X552015Y-267323D01*
X517520D01*
Y-278740D01*
X520620D01*
Y-284252D01*
X520620Y-284252D01*
X520728Y-284798D01*
X521038Y-285261D01*
X521654Y-285877D01*
Y-294045D01*
X529932D01*
X530063Y-294132D01*
X530609Y-294241D01*
X530609Y-294241D01*
X532776D01*
Y-300787D01*
Y-302953D01*
X531250D01*
Y-314567D01*
X517373D01*
X512598Y-309792D01*
Y-304966D01*
X513014Y-304689D01*
X513048Y-304702D01*
X513764D01*
X514426Y-304428D01*
X514932Y-303922D01*
X515206Y-303260D01*
Y-302544D01*
X514932Y-301883D01*
X514426Y-301376D01*
X513764Y-301102D01*
X513624D01*
X512598Y-300076D01*
Y-287402D01*
X504381D01*
X502953Y-285973D01*
Y-267323D01*
X497429D01*
X497003Y-267209D01*
X495910D01*
X495484Y-267323D01*
X492520D01*
Y-259732D01*
Y-249065D01*
X496850D01*
X496850Y-249065D01*
X497397Y-248957D01*
X497860Y-248647D01*
X500616Y-245891D01*
X500616Y-245891D01*
X500793Y-245626D01*
X501128Y-245291D01*
X501128Y-245291D01*
X501438Y-244828D01*
X501546Y-244281D01*
X501546Y-244281D01*
Y-241339D01*
X546850D01*
Y-251181D01*
D02*
G37*
G36*
X584848Y-279831D02*
X585433Y-279947D01*
X587625D01*
X587865Y-280144D01*
Y-282074D01*
X579858D01*
Y-279520D01*
X584383D01*
X584848Y-279831D01*
D02*
G37*
%LPC*%
G36*
X379854Y-177415D02*
X379138D01*
X378477Y-177689D01*
X377970Y-178195D01*
X377696Y-178857D01*
Y-179573D01*
X377970Y-180234D01*
X378477Y-180740D01*
X379138Y-181015D01*
X379854D01*
X380516Y-180740D01*
X381022Y-180234D01*
X381296Y-179573D01*
Y-178857D01*
X381022Y-178195D01*
X380516Y-177689D01*
X379854Y-177415D01*
D02*
G37*
G36*
X370339Y-177415D02*
X369623D01*
X368961Y-177689D01*
X368455Y-178196D01*
X368181Y-178857D01*
Y-179573D01*
X368455Y-180235D01*
X368961Y-180741D01*
X369623Y-181015D01*
X370339D01*
X371000Y-180741D01*
X371507Y-180235D01*
X371781Y-179573D01*
Y-178857D01*
X371507Y-178196D01*
X371000Y-177689D01*
X370339Y-177415D01*
D02*
G37*
G36*
X360496D02*
X359780D01*
X359119Y-177689D01*
X358612Y-178196D01*
X358338Y-178857D01*
Y-179573D01*
X358612Y-180235D01*
X359119Y-180741D01*
X359780Y-181015D01*
X360496D01*
X361158Y-180741D01*
X361664Y-180235D01*
X361938Y-179573D01*
Y-178857D01*
X361664Y-178196D01*
X361158Y-177689D01*
X360496Y-177415D01*
D02*
G37*
G36*
X370043Y-182041D02*
X369327D01*
X368666Y-182315D01*
X368159Y-182822D01*
X367885Y-183483D01*
Y-184199D01*
X368159Y-184861D01*
X368666Y-185367D01*
X369327Y-185641D01*
X370043D01*
X370705Y-185367D01*
X371211Y-184861D01*
X371485Y-184199D01*
Y-183483D01*
X371211Y-182822D01*
X370705Y-182315D01*
X370043Y-182041D01*
D02*
G37*
G36*
X360232D02*
X359516D01*
X358855Y-182315D01*
X358348Y-182822D01*
X358074Y-183483D01*
Y-184199D01*
X358348Y-184861D01*
X358855Y-185367D01*
X359516Y-185641D01*
X360232D01*
X360894Y-185367D01*
X361400Y-184861D01*
X361674Y-184199D01*
Y-183483D01*
X361400Y-182822D01*
X360894Y-182315D01*
X360232Y-182041D01*
D02*
G37*
G36*
X362957Y-195444D02*
X362240D01*
X361579Y-195718D01*
X361072Y-196224D01*
X360798Y-196886D01*
Y-197602D01*
X361072Y-198264D01*
X361579Y-198770D01*
X362240Y-199044D01*
X362957D01*
X363618Y-198770D01*
X364124Y-198264D01*
X364398Y-197602D01*
Y-196886D01*
X364124Y-196224D01*
X363618Y-195718D01*
X362957Y-195444D01*
D02*
G37*
G36*
X376056Y-195900D02*
X375340D01*
X374678Y-196174D01*
X374172Y-196680D01*
X373898Y-197342D01*
Y-198058D01*
X374172Y-198720D01*
X374678Y-199226D01*
X375340Y-199500D01*
X376056D01*
X376718Y-199226D01*
X377224Y-198720D01*
X377498Y-198058D01*
Y-197342D01*
X377224Y-196680D01*
X376718Y-196174D01*
X376056Y-195900D01*
D02*
G37*
G36*
X374088Y-201088D02*
X373372D01*
X372710Y-201362D01*
X372204Y-201869D01*
X371930Y-202530D01*
Y-203246D01*
X372204Y-203908D01*
X372710Y-204414D01*
X373372Y-204688D01*
X374088D01*
X374750Y-204414D01*
X375256Y-203908D01*
X375530Y-203246D01*
Y-202530D01*
X375256Y-201869D01*
X374750Y-201362D01*
X374088Y-201088D01*
D02*
G37*
G36*
X375555Y-219460D02*
X374839D01*
X374177Y-219734D01*
X373671Y-220240D01*
X373397Y-220902D01*
Y-221618D01*
X373671Y-222280D01*
X374177Y-222786D01*
X374839Y-223060D01*
X375555D01*
X376217Y-222786D01*
X376723Y-222280D01*
X376997Y-221618D01*
Y-220902D01*
X376723Y-220240D01*
X376217Y-219734D01*
X375555Y-219460D01*
D02*
G37*
G36*
X524374Y-241999D02*
X523658D01*
X522996Y-242273D01*
X522490Y-242780D01*
X522216Y-243441D01*
Y-244157D01*
X522490Y-244819D01*
X522996Y-245325D01*
X523658Y-245599D01*
X524374D01*
X525035Y-245325D01*
X525542Y-244819D01*
X525816Y-244157D01*
Y-243441D01*
X525542Y-242780D01*
X525035Y-242273D01*
X524374Y-241999D01*
D02*
G37*
G36*
X535528Y-243193D02*
X530969D01*
Y-247555D01*
X535528D01*
Y-247414D01*
X536028Y-247079D01*
X536256Y-247174D01*
X536972D01*
X537634Y-246900D01*
X538140Y-246394D01*
X538414Y-245732D01*
Y-245016D01*
X538140Y-244354D01*
X537634Y-243848D01*
X536972Y-243574D01*
X536256D01*
X536028Y-243669D01*
X535528Y-243334D01*
Y-243193D01*
D02*
G37*
G36*
X522405Y-247905D02*
X521689D01*
X521028Y-248179D01*
X520521Y-248685D01*
X520247Y-249347D01*
Y-250063D01*
X520521Y-250724D01*
X521028Y-251231D01*
X521689Y-251505D01*
X522405D01*
X523067Y-251231D01*
X523573Y-250724D01*
X523847Y-250063D01*
Y-249347D01*
X523573Y-248685D01*
X523067Y-248179D01*
X522405Y-247905D01*
D02*
G37*
G36*
X537536Y-248705D02*
X532977D01*
Y-253067D01*
X537536D01*
Y-252698D01*
X537727Y-252568D01*
X538036Y-252445D01*
X538618Y-252686D01*
X539334D01*
X539996Y-252412D01*
X540502Y-251905D01*
X540776Y-251244D01*
Y-250528D01*
X540502Y-249866D01*
X539996Y-249360D01*
X539334Y-249086D01*
X538618D01*
X538036Y-249327D01*
X537727Y-249203D01*
X537536Y-249073D01*
Y-248705D01*
D02*
G37*
G36*
X508626Y-249873D02*
X507910D01*
X507248Y-250147D01*
X506742Y-250654D01*
X506468Y-251315D01*
Y-252031D01*
X506742Y-252693D01*
X507248Y-253199D01*
X507910Y-253473D01*
X508626D01*
X509287Y-253199D01*
X509794Y-252693D01*
X510068Y-252031D01*
Y-251315D01*
X509794Y-250654D01*
X509287Y-250147D01*
X508626Y-249873D01*
D02*
G37*
G36*
X513744Y-252629D02*
X513028D01*
X512366Y-252903D01*
X511860Y-253410D01*
X511586Y-254071D01*
Y-254787D01*
X511860Y-255449D01*
X512366Y-255955D01*
X513028Y-256229D01*
X513744D01*
X514405Y-255955D01*
X514912Y-255449D01*
X515186Y-254787D01*
Y-254071D01*
X514912Y-253410D01*
X514405Y-252903D01*
X513744Y-252629D01*
D02*
G37*
G36*
X518468Y-253416D02*
X517752D01*
X517091Y-253691D01*
X516584Y-254197D01*
X516310Y-254858D01*
Y-255575D01*
X516584Y-256236D01*
X517091Y-256743D01*
X517752Y-257016D01*
X518468D01*
X519130Y-256743D01*
X519636Y-256236D01*
X519910Y-255575D01*
Y-254858D01*
X519636Y-254197D01*
X519130Y-253691D01*
X518468Y-253416D01*
D02*
G37*
G36*
X497949Y-250354D02*
X493661D01*
Y-254370D01*
X493661D01*
X493987Y-254870D01*
X493869Y-255154D01*
Y-255870D01*
X494143Y-256531D01*
X494650Y-257038D01*
X495311Y-257312D01*
X496027D01*
X496689Y-257038D01*
X497195Y-256531D01*
X497469Y-255870D01*
Y-255154D01*
X497352Y-254870D01*
X497686Y-254370D01*
X497949D01*
Y-250354D01*
D02*
G37*
G36*
X550358Y-253810D02*
X549642D01*
X548980Y-254084D01*
X548474Y-254591D01*
X548200Y-255252D01*
Y-255968D01*
X548474Y-256630D01*
X548980Y-257136D01*
X549642Y-257410D01*
X550358D01*
X551020Y-257136D01*
X551526Y-256630D01*
X551800Y-255968D01*
Y-255252D01*
X551526Y-254591D01*
X551020Y-254084D01*
X550358Y-253810D01*
D02*
G37*
G36*
X538714Y-253823D02*
X534155D01*
Y-258185D01*
X538714D01*
Y-257431D01*
X539827D01*
X539925Y-257530D01*
X540587Y-257804D01*
X541303D01*
X541964Y-257530D01*
X542471Y-257024D01*
X542745Y-256362D01*
Y-255646D01*
X542471Y-254984D01*
X541964Y-254478D01*
X541303Y-254204D01*
X540587D01*
X539925Y-254478D01*
X539827Y-254576D01*
X538714D01*
Y-253823D01*
D02*
G37*
G36*
X508232Y-254105D02*
X507516D01*
X506854Y-254380D01*
X506348Y-254886D01*
X506074Y-255547D01*
Y-256263D01*
X506348Y-256925D01*
X506854Y-257432D01*
X507329Y-257628D01*
X507230Y-258128D01*
X506973D01*
Y-262144D01*
X511260D01*
Y-258128D01*
X510646D01*
Y-255906D01*
X510529Y-255320D01*
X510198Y-254824D01*
X509702Y-254492D01*
X509116Y-254376D01*
X508885D01*
X508232Y-254105D01*
D02*
G37*
G36*
X576910Y-259114D02*
X572622D01*
Y-263130D01*
X576910D01*
Y-263066D01*
X577070Y-262944D01*
X577410Y-262801D01*
X577974Y-263035D01*
X578690D01*
X579351Y-262761D01*
X579858Y-262255D01*
X580132Y-261593D01*
Y-260877D01*
X579858Y-260215D01*
X579351Y-259709D01*
X578690Y-259435D01*
X577974D01*
X577593Y-259593D01*
X576910D01*
Y-259114D01*
D02*
G37*
G36*
X564531Y-254105D02*
X563815D01*
X563154Y-254380D01*
X562647Y-254886D01*
X562373Y-255547D01*
Y-256263D01*
X562647Y-256925D01*
X562976Y-257254D01*
Y-259111D01*
X562362D01*
Y-263127D01*
X566650D01*
Y-259111D01*
X566035D01*
Y-255906D01*
X565973Y-255594D01*
Y-255547D01*
X565955Y-255504D01*
X565919Y-255320D01*
X565814Y-255164D01*
X565699Y-254886D01*
X565193Y-254380D01*
X564531Y-254105D01*
D02*
G37*
G36*
X498343Y-257834D02*
X494055D01*
Y-258591D01*
X493800Y-258761D01*
X493469Y-259257D01*
X493353Y-259842D01*
Y-261292D01*
X493082Y-261945D01*
Y-262661D01*
X493356Y-263323D01*
X493862Y-263829D01*
X494524Y-264103D01*
X495240D01*
X495901Y-263829D01*
X496408Y-263323D01*
X496682Y-262661D01*
Y-261945D01*
X496745Y-261851D01*
X498343D01*
Y-257834D01*
D02*
G37*
G36*
X529318Y-295041D02*
X528602D01*
X527941Y-295315D01*
X527434Y-295821D01*
X527160Y-296483D01*
Y-297199D01*
X527434Y-297860D01*
X527941Y-298367D01*
X528602Y-298641D01*
X529318D01*
X529980Y-298367D01*
X530486Y-297860D01*
X530760Y-297199D01*
Y-296483D01*
X530486Y-295821D01*
X529980Y-295315D01*
X529318Y-295041D01*
D02*
G37*
G36*
X523193Y-295936D02*
X522477D01*
X521815Y-296210D01*
X521309Y-296717D01*
X521035Y-297378D01*
Y-298094D01*
X521309Y-298756D01*
X521815Y-299262D01*
X522477Y-299536D01*
X523193D01*
X523854Y-299262D01*
X524361Y-298756D01*
X524635Y-298094D01*
Y-297378D01*
X524361Y-296717D01*
X523854Y-296210D01*
X523193Y-295936D01*
D02*
G37*
G36*
X517287Y-296330D02*
X516571D01*
X515909Y-296604D01*
X515403Y-297110D01*
X515129Y-297772D01*
Y-298488D01*
X515403Y-299149D01*
X515909Y-299656D01*
X516571Y-299930D01*
X517287D01*
X517949Y-299656D01*
X518455Y-299149D01*
X518729Y-298488D01*
Y-297772D01*
X518455Y-297110D01*
X517949Y-296604D01*
X517287Y-296330D01*
D02*
G37*
%LPD*%
D11*
X260561Y-390826D02*
G03*
X259287Y-390247I-1413J-1416D01*
G01*
X215115Y-391673D02*
G03*
X214252Y-393318I1137J-1645D01*
G01*
X593307Y-292126D02*
X594255D01*
X595946Y-290435D01*
Y-287918D01*
X596220Y-287644D01*
X601575Y-271682D02*
Y-256498D01*
Y-279588D02*
Y-271682D01*
X580866Y-276053D02*
X580874Y-276045D01*
Y-273457D02*
X581496Y-272835D01*
X580874Y-276045D02*
Y-273457D01*
X580866Y-287250D02*
X581190Y-287574D01*
Y-289457D02*
Y-287574D01*
Y-289457D02*
X581890Y-290158D01*
X596220Y-281797D02*
Y-279718D01*
Y-283876D02*
Y-281797D01*
X580866Y-283482D02*
Y-278931D01*
X601575Y-291339D02*
Y-279588D01*
X596220Y-279718D02*
X601444D01*
X601575Y-279588D01*
X611408Y-302756D02*
X612781D01*
X610236Y-301584D02*
Y-300000D01*
Y-301584D02*
X611408Y-302756D01*
X250521Y-390945D02*
X251456Y-390009D01*
X247241Y-390945D02*
X250521D01*
X249730Y-391658D02*
X250482Y-390906D01*
X246006Y-392179D02*
X247241Y-390945D01*
X245669Y-401427D02*
X246006Y-401090D01*
Y-392179D01*
X259285Y-390247D02*
X259287Y-390247D01*
X260561Y-390826D02*
X260562Y-390828D01*
X277289Y-404055D02*
Y-401303D01*
X226063Y-404100D02*
Y-390722D01*
X233937Y-404100D02*
Y-391623D01*
X214252Y-404100D02*
Y-393318D01*
X202441Y-404100D02*
Y-390600D01*
X163071Y-404100D02*
Y-390730D01*
X214252Y-393318D02*
Y-393318D01*
X407874Y-216535D02*
X413386D01*
X424409Y-205512D01*
X601575Y-291339D02*
X610236Y-300000D01*
X601575Y-256498D02*
X605317Y-252756D01*
X617894D02*
X618288Y-252362D01*
X618504D01*
X605317Y-252756D02*
X617894D01*
X260562Y-390828D02*
X261343Y-391608D01*
X215115Y-391673D02*
X216162Y-390947D01*
X233937Y-391623D02*
X235144Y-390416D01*
X277387Y-392067D02*
X279445Y-390009D01*
X281201D01*
X264954Y-401027D02*
Y-392780D01*
X263783Y-391608D02*
X264954Y-392780D01*
X277289Y-401303D02*
X277387Y-401205D01*
X264954Y-401027D02*
X265354Y-401427D01*
X261343Y-401353D02*
X261417Y-401427D01*
X261343Y-401353D02*
Y-391608D01*
X263783D01*
X277387Y-401205D02*
Y-392067D01*
X277244Y-404100D02*
X277289Y-404055D01*
X249730Y-401303D02*
Y-391658D01*
X249606Y-401427D02*
X249730Y-401303D01*
X277165Y-401427D02*
X277289Y-401303D01*
X159134Y-404100D02*
Y-390901D01*
X155197Y-389452D02*
X156441Y-388208D01*
X159134Y-390901D01*
X155197Y-404100D02*
Y-389452D01*
D16*
X256941Y-400125D02*
G03*
X257480Y-401427I1841J0D01*
G01*
X237941Y-378907D02*
G03*
X237992Y-378783I-124J124D01*
G01*
X206441Y-378907D02*
G03*
X206496Y-378774I-133J133D01*
G01*
X218439Y-374114D02*
G03*
X218310Y-374444I371J-335D01*
G01*
X256890Y-378783D02*
G03*
X256941Y-378907I175J0D01*
G01*
X253346Y-378679D02*
G03*
X253441Y-378907I323J0D01*
G01*
X253655Y-374421D02*
G03*
X253346Y-374879I191J-462D01*
G01*
X269496Y-374321D02*
G03*
X269488Y-374409I492J-88D01*
G01*
X269441Y-378907D02*
G03*
X269488Y-378793I-114J114D01*
G01*
X241811Y-404100D02*
G03*
X241941Y-403786I-314J314D01*
G01*
X273441Y-382293D02*
G03*
X273307Y-382616I323J-323D01*
G01*
X269441Y-382293D02*
G03*
X269370Y-382464I171J-171D01*
G01*
X253622Y-382730D02*
G03*
X253441Y-382293I-618J0D01*
G01*
Y-401180D02*
G03*
X253543Y-401427I349J0D01*
G01*
X206441Y-382293D02*
G03*
X206378Y-382445I152J-152D01*
G01*
X206299Y-401427D02*
G03*
X206441Y-401085I-342J342D01*
G01*
X210236Y-401427D02*
G03*
X210441Y-400933I-494J494D01*
G01*
X218110Y-401427D02*
G03*
X218341Y-400870I-557J557D01*
G01*
X222047Y-401427D02*
G03*
X222641Y-399993I-1433J1433D01*
G01*
X237795Y-401427D02*
G03*
X237941Y-401075I-352J352D01*
G01*
X241732Y-401427D02*
G03*
X241941Y-400923I-504J504D01*
G01*
X273228Y-401427D02*
G03*
X273441Y-400913I-514J514D01*
G01*
X269291Y-401427D02*
G03*
X269441Y-401065I-362J362D01*
G01*
X269370Y-404100D02*
G03*
X269441Y-403929I-171J171D01*
G01*
X218189Y-404100D02*
G03*
X218341Y-403733I-367J367D01*
G01*
X237874Y-404100D02*
G03*
X237941Y-403938I-162J162D01*
G01*
X256941Y-402608D02*
G03*
X257557Y-404098I2110J0D01*
G01*
D02*
G03*
X257559Y-404100I1494J1490D01*
G01*
X256941Y-400125D02*
Y-382293D01*
X237992Y-378783D02*
Y-374655D01*
X241929Y-378895D02*
X241941Y-378907D01*
X241929Y-378895D02*
Y-374655D01*
X206496Y-378774D02*
Y-374655D01*
X210433Y-378899D02*
Y-374655D01*
Y-378899D02*
X210441Y-378907D01*
X218439Y-374114D02*
X218444Y-374109D01*
X218307Y-374706D02*
X218310Y-374444D01*
X218444Y-374109D02*
X218445Y-374108D01*
X218307Y-378873D02*
Y-374706D01*
Y-378873D02*
X218341Y-378907D01*
X222638Y-378904D02*
X222641Y-378907D01*
X222638Y-378904D02*
Y-374655D01*
X256890Y-378783D02*
Y-374655D01*
X253346Y-378679D02*
Y-374879D01*
X269496Y-374321D02*
X269501Y-374292D01*
X269488Y-378793D02*
Y-374409D01*
X269501Y-374292D02*
X269502Y-374291D01*
X273425Y-378891D02*
Y-374655D01*
Y-378891D02*
X273441Y-378907D01*
Y-400913D02*
Y-382293D01*
X269441Y-401065D02*
Y-382293D01*
X253441Y-401180D02*
Y-382293D01*
X206441Y-401085D02*
Y-382293D01*
X210441Y-400933D02*
Y-382293D01*
X218341Y-400870D02*
Y-382293D01*
X222641Y-399993D02*
Y-382293D01*
X237941Y-401075D02*
Y-382293D01*
X241941Y-400923D02*
Y-382293D01*
D18*
X182677Y-391100D02*
Y-389062D01*
Y-401427D02*
Y-391100D01*
X186614Y-401427D02*
Y-391686D01*
X186028Y-391100D02*
X186614Y-391686D01*
X182677Y-391100D02*
X186028D01*
X181534Y-387919D02*
X182677Y-389062D01*
X181534Y-387919D02*
Y-387757D01*
X444095Y-121653D02*
X449606D01*
X425197Y-105512D02*
X427953D01*
X444095Y-121653D01*
X427165Y-124803D02*
X449606D01*
X414725Y-112363D02*
Y-104643D01*
Y-112363D02*
X427165Y-124803D01*
X452854Y-144390D02*
Y-131595D01*
X449606Y-128347D02*
X452854Y-131595D01*
X441732Y-144390D02*
Y-132283D01*
X445669Y-128347D01*
X427559Y-148819D02*
X430709D01*
X435138Y-144390D02*
X437303D01*
X430709Y-148819D02*
X435138Y-144390D01*
X427843Y-166966D02*
X431497Y-163312D01*
Y-161216D01*
X435500Y-157213D02*
X444788D01*
X431497Y-161216D02*
X435500Y-157213D01*
X445374Y-156627D02*
Y-154331D01*
X444788Y-157213D02*
X445374Y-156627D01*
X452854Y-147835D02*
Y-147736D01*
X447039Y-153650D02*
X452854Y-147835D01*
X446055Y-153650D02*
X447039D01*
X445374Y-154331D02*
X446055Y-153650D01*
X422835Y-166284D02*
Y-166122D01*
X423864Y-165093D01*
Y-163878D01*
X431102Y-156895D02*
Y-154035D01*
X430517Y-157480D02*
X431102Y-156895D01*
X430261Y-157480D02*
X430517D01*
X423864Y-163878D02*
X430261Y-157480D01*
X431102Y-154035D02*
X437303Y-147835D01*
Y-147736D01*
X441732D02*
X441732Y-147736D01*
X437303Y-147736D02*
X441732D01*
X441373Y-153676D02*
X442028Y-154331D01*
X439248Y-153676D02*
X441373D01*
X439115Y-153543D02*
X439248Y-153676D01*
X436811Y-153543D02*
X439115D01*
X441732Y-147736D02*
X441782Y-147687D01*
X437303Y-144390D02*
Y-144291D01*
X68405Y-2165D02*
Y787D01*
X64862Y-5709D02*
X64961D01*
X65642Y-5028D01*
Y-4929D01*
X68405Y-2165D01*
X68307Y787D02*
X68405D01*
X61811D02*
X68307D01*
X49508Y-3642D02*
Y394D01*
X47441Y-5709D02*
X49508Y-3642D01*
X56693Y-5709D02*
Y1060D01*
X52854Y394D02*
X55865D01*
X56531Y1060D01*
X56693D01*
X71752Y-2067D02*
Y787D01*
Y-2067D02*
X75394Y-5709D01*
X102683Y394D02*
X108268D01*
X92732Y-9557D02*
X102683Y394D01*
X92732Y-13129D02*
Y-9557D01*
Y-13129D02*
X92782Y-13179D01*
Y-16880D02*
Y-13179D01*
Y-16880D02*
X92831Y-16929D01*
X53248Y-8850D02*
Y-5709D01*
Y-15453D02*
Y-8850D01*
X53453Y-9055D02*
X60630D01*
X53248Y-8850D02*
X53453Y-9055D01*
X61516Y-8169D02*
Y-5709D01*
X60630Y-9055D02*
X61516Y-8169D01*
X47441Y-21260D02*
X53248Y-15453D01*
X570676Y-278550D02*
X575086D01*
X172939Y-127362D02*
Y-124276D01*
Y-127362D02*
X173461D01*
X172939Y-117450D02*
Y-117323D01*
Y-120812D02*
Y-117450D01*
X171629Y-118760D02*
X172939Y-117450D01*
Y-117323D02*
X173228D01*
X499077Y-259842D02*
Y-257606D01*
X500049Y-256633D01*
X575591Y-266142D02*
X585039D01*
X554572Y-266929D02*
X574803D01*
X575591Y-266142D01*
X550000Y-275700D02*
Y-271501D01*
X554572Y-266929D01*
X545669Y-280030D02*
X550000Y-275700D01*
X560630Y-269291D02*
X566929D01*
X554331D02*
X560630D01*
X596063Y-273622D02*
X598003Y-271682D01*
X601575D01*
X589370Y-273622D02*
X596063D01*
X585433Y-269685D02*
X589370Y-273622D01*
X596220Y-276840D02*
Y-276705D01*
X597779Y-275146D01*
X598930D01*
X599044Y-275032D01*
X580315Y-269685D02*
X585433D01*
X578740Y-274896D02*
Y-271260D01*
X580315Y-269685D01*
X575086Y-278550D02*
X578740Y-274896D01*
X587413Y-274421D02*
X589652Y-276660D01*
X585039Y-272835D02*
X585120D01*
X586706Y-274421D01*
X587413D01*
X570676Y-278550D02*
X570806Y-278420D01*
X572761D01*
X578109Y-283482D02*
X580866D01*
X576575Y-285016D02*
X578109Y-283482D01*
X575878Y-292709D02*
X576575Y-292012D01*
Y-285016D01*
X554773Y-292709D02*
X575878D01*
X530684Y-289075D02*
X551139D01*
X554773Y-292709D01*
X526799Y-285190D02*
X530684Y-289075D01*
X526799Y-285190D02*
Y-276255D01*
X527385Y-275669D01*
X530984D01*
X548425Y-269632D02*
Y-267717D01*
Y-271037D02*
Y-269632D01*
X544471Y-273290D02*
X544756Y-273005D01*
X546457D01*
X548425Y-271037D01*
X546161Y-265453D02*
X548425Y-267717D01*
X527953Y-269291D02*
X531791Y-265453D01*
X546161D01*
X527953Y-271952D02*
Y-269291D01*
X530854Y-273571D02*
X530984Y-273701D01*
X529572Y-273571D02*
X530854D01*
X527953Y-271952D02*
X529572Y-273571D01*
X541347Y-282669D02*
X542126Y-281890D01*
X541347Y-284211D02*
Y-282669D01*
X541093Y-284464D02*
X541347Y-284211D01*
X541093Y-284626D02*
Y-284464D01*
X541411Y-269932D02*
X541891Y-270412D01*
X544471D01*
X536772Y-271732D02*
Y-269627D01*
X536489Y-269344D02*
X536772Y-269627D01*
X536489Y-269344D02*
Y-269182D01*
X536772Y-273701D02*
X536902Y-273571D01*
X544190D01*
X544471Y-273290D01*
X536772Y-277638D02*
X541597D01*
X542503Y-278544D01*
X536203Y-282481D02*
Y-277768D01*
X536333Y-277638D01*
X536772D01*
X566929Y-269291D02*
X568184Y-270546D01*
Y-272062D02*
X568963Y-272841D01*
X568184Y-272062D02*
Y-270546D01*
X551700Y-277617D02*
Y-271922D01*
X554331Y-269291D01*
X552633Y-278550D02*
X564889D01*
X551700Y-277617D02*
X552633Y-278550D01*
X554757Y-275564D02*
X554790Y-275597D01*
X554757Y-275564D02*
Y-272474D01*
X554724Y-272441D02*
X554757Y-272474D01*
X555460Y-284401D02*
X555497Y-284364D01*
Y-280755D01*
X574406Y-286322D02*
Y-280807D01*
X571654Y-289075D02*
X574406Y-286322D01*
X561811Y-289075D02*
X571654D01*
X558375Y-285639D02*
Y-280755D01*
Y-285639D02*
X561811Y-289075D01*
X574118Y-280519D02*
X574406Y-280807D01*
X570676Y-280519D02*
X574118D01*
X567305Y-286203D02*
X567525D01*
X564889Y-282487D02*
X565558D01*
X565688Y-282617D01*
Y-284585D02*
Y-282617D01*
Y-284585D02*
X567305Y-286203D01*
X558375Y-280755D02*
X563983D01*
X564219Y-280519D01*
X564889D01*
X558727Y-275597D02*
X561414Y-272910D01*
X564958D01*
Y-276513D02*
Y-272910D01*
X564889Y-276582D02*
X564958Y-276513D01*
X568963Y-272841D02*
X570676Y-274554D01*
Y-276582D02*
Y-274554D01*
X596220Y-279718D02*
Y-279583D01*
X595712Y-279075D02*
X596220Y-279583D01*
X594287Y-279075D02*
X595712D01*
X593630Y-278418D02*
X594287Y-279075D01*
X591680Y-278418D02*
X593630D01*
X591680Y-281567D02*
X595991D01*
X596220Y-281797D01*
X589652Y-279992D02*
Y-276660D01*
X583815Y-275402D02*
Y-275386D01*
Y-275402D02*
X585433Y-277020D01*
Y-278418D02*
Y-277020D01*
Y-278418D02*
X587625D01*
X249213Y-113386D02*
X251039Y-115212D01*
X245587Y-98736D02*
X249213Y-102362D01*
Y-113386D02*
Y-102362D01*
X222351Y-98694D02*
X222393Y-98736D01*
X245587D01*
X43701Y-138046D02*
X44001Y-137747D01*
X43701Y-148819D02*
Y-138046D01*
X251039Y-149554D02*
Y-115212D01*
Y-149554D02*
X265570Y-164085D01*
X299306D01*
X305692Y-157698D01*
Y-123172D01*
X298031Y-115512D02*
X305692Y-123172D01*
X35433Y-150394D02*
Y-129528D01*
X39370Y-154331D02*
X43701D01*
X35433Y-150394D02*
X39370Y-154331D01*
X157538Y-121632D02*
X157713Y-121457D01*
X153225Y-121747D02*
X153340Y-121632D01*
X157538D01*
X149213Y-114961D02*
Y-109345D01*
X151725Y-106833D02*
X155716D01*
X149213Y-109345D02*
X151725Y-106833D01*
X155716D02*
X158661Y-103887D01*
Y-101429D01*
X608268Y-64961D02*
Y-59842D01*
Y-70079D02*
Y-64961D01*
X598425Y-79921D02*
X603357D01*
X383083Y-135039D02*
Y-128504D01*
X383201Y-141339D02*
Y-135039D01*
X564506Y-261119D02*
Y-255906D01*
X574766Y-261122D02*
X578332D01*
X495669Y-255512D02*
Y-252362D01*
X509116Y-260136D02*
Y-255906D01*
X494882Y-262303D02*
Y-259842D01*
X203937Y-1514D02*
Y1969D01*
X204537Y-79380D02*
Y-76439D01*
X46417Y-43355D02*
X50000D01*
X64528Y-53218D02*
X72795D01*
X59016Y-54241D02*
X64528D01*
X217405Y-138189D02*
Y-134835D01*
X603150Y-235946D02*
X603268D01*
X604252Y-236929D01*
Y-239054D02*
Y-236929D01*
X604252Y-246535D02*
X604316Y-246600D01*
X604252Y-246535D02*
Y-242991D01*
X35433Y-50787D02*
X44022D01*
X45275Y-49534D01*
Y-49498D01*
X46417Y-48355D01*
X149924Y-124213D02*
X149931Y-124206D01*
X149935D01*
X150233Y-119882D02*
X154343D01*
X155622Y-118602D01*
X422835Y-144095D02*
X431943D01*
Y-132677D01*
X50000Y-44094D02*
Y-43355D01*
X263327Y-231496D02*
X277187Y-217637D01*
X284533D01*
X297638Y-204532D01*
Y-193307D01*
X295669Y-191339D02*
X297638Y-193307D01*
X174221Y-334252D02*
Y-297827D01*
X241339Y-247638D02*
X257480Y-231496D01*
X201969Y-270079D02*
X230929D01*
X257480Y-231496D02*
X263327D01*
X230929Y-270079D02*
X241339Y-259669D01*
X174221Y-297827D02*
X201969Y-270079D01*
X241339Y-259669D02*
Y-247638D01*
X623465Y-338403D02*
X625816Y-340754D01*
X601033Y-356690D02*
X601430Y-357087D01*
X623228D02*
X625816Y-354499D01*
X623465Y-338403D02*
Y-333307D01*
X579072Y-356690D02*
X601033D01*
X625816Y-354499D02*
Y-340754D01*
X601430Y-357087D02*
X623228D01*
X546850Y-348819D02*
X587402D01*
X596102Y-340118D02*
Y-333464D01*
X544685Y-350984D02*
X546850Y-348819D01*
X539243Y-350984D02*
X544685D01*
X596102Y-333464D02*
X600039Y-329528D01*
X587402Y-348819D02*
X596102Y-340118D01*
X606961Y-329528D02*
X623008Y-313481D01*
X600039Y-329528D02*
X606961D01*
X533931Y-356296D02*
X539243Y-350984D01*
X603696Y-351181D02*
X605822Y-353307D01*
X473241Y-356693D02*
X477203Y-360655D01*
X594882Y-351181D02*
X603696D01*
X591677Y-354386D02*
X594882Y-351181D01*
X449310Y-355832D02*
X450171Y-356693D01*
X605822Y-353307D02*
X623541D01*
X562967Y-360655D02*
X569236Y-354386D01*
X591677D01*
X477203Y-360655D02*
X562967D01*
X449150Y-355832D02*
X449310D01*
X450171Y-356693D02*
X473241D01*
X347872Y-242913D02*
X384744D01*
X390896Y-249065D01*
X340786Y-235827D02*
X347872Y-242913D01*
X379497Y-245276D02*
X383334Y-249113D01*
X343637Y-245276D02*
X379497D01*
X341274Y-242913D02*
X343637Y-245276D01*
X383334Y-249113D02*
X386615D01*
X296350Y-272153D02*
X298819Y-269685D01*
X293268Y-273071D02*
X294185Y-272153D01*
X293268Y-273622D02*
Y-273071D01*
X294185Y-272153D02*
X296350D01*
X168441Y-118760D02*
X171629D01*
X146063Y-118110D02*
X149213Y-114961D01*
X146063Y-138976D02*
Y-118110D01*
Y-138976D02*
X150000Y-142913D01*
X166178D01*
X167949Y-141142D01*
X165823Y-121457D02*
X168441Y-118839D01*
X160863Y-121457D02*
X165823D01*
X168441Y-118839D02*
Y-118760D01*
X153150Y-113386D02*
X155217Y-115453D01*
X158008D01*
X164773Y-117570D02*
Y-114161D01*
X210236Y-36986D02*
X212278Y-34944D01*
X215354D01*
X210236Y-37085D02*
Y-36986D01*
X215354Y-34846D02*
X217575Y-32626D01*
X215354Y-34944D02*
Y-34846D01*
X217575Y-32626D02*
X220866D01*
X226327D02*
X226378Y-32677D01*
X220866Y-32626D02*
X226327D01*
X532009Y-250886D02*
X532690Y-251567D01*
Y-252925D02*
X533088Y-253323D01*
X531910Y-250886D02*
X532009D01*
X532690Y-252925D02*
Y-251567D01*
X533088Y-256004D02*
Y-253323D01*
X529902Y-248976D02*
X531812Y-250886D01*
X529902Y-248976D02*
Y-245374D01*
X531812Y-250886D02*
X531910D01*
X530535Y-242693D02*
X531102Y-242126D01*
X530535Y-244741D02*
Y-242693D01*
X529902Y-245374D02*
X530535Y-244741D01*
X618504Y-231102D02*
X622835Y-235433D01*
X615765Y-231102D02*
X618504D01*
X616990Y-241006D02*
X622803D01*
X614431Y-238583D02*
X614567D01*
X616990Y-241006D01*
X586221Y-178740D02*
X586319Y-178642D01*
X589764D01*
X586614Y-158661D02*
X586698Y-158745D01*
X589730D01*
X579134Y-214006D02*
X579301Y-214173D01*
X582382D01*
X581890Y-240059D02*
Y-235925D01*
X584646Y-228937D02*
Y-225197D01*
X590173Y-224296D02*
Y-221177D01*
X590188Y-221161D01*
X590158Y-224311D02*
X590173Y-224296D01*
X582382Y-202658D02*
X583957Y-201083D01*
X582382Y-206693D02*
Y-202658D01*
X583957Y-201083D02*
Y-196850D01*
X583858Y-192913D02*
X583957Y-193012D01*
Y-196850D02*
Y-193012D01*
X598411Y-83085D02*
X598425Y-83071D01*
X598397Y-88288D02*
X598411Y-88273D01*
Y-83085D01*
X603357Y-83008D02*
X603450Y-83101D01*
Y-87702D02*
Y-83101D01*
Y-87702D02*
X603543Y-87795D01*
X425938Y-194488D02*
Y-190204D01*
X428346Y-187795D01*
X189764Y-93049D02*
Y-88189D01*
X151766Y5398D02*
Y10428D01*
X151751Y5383D02*
X151766Y5398D01*
Y10428D02*
X151782Y10443D01*
X479331Y-294789D02*
Y-294626D01*
X477872Y-298948D02*
Y-296247D01*
X479331Y-294789D01*
X479308Y-294649D02*
X479331Y-294626D01*
X481754Y-265748D02*
X486221D01*
X118110Y-36220D02*
X118110D01*
X117717Y-47293D02*
X117825Y-47401D01*
X564173Y-255906D02*
X564506D01*
X578332Y-261235D02*
Y-261122D01*
X571888D02*
Y-256791D01*
X571260D02*
X571888D01*
X567384Y-261119D02*
Y-256791D01*
X568898D01*
X495669Y-252362D02*
X495805D01*
X507874Y-255906D02*
X509116D01*
X494882Y-259842D02*
X496199D01*
X498683Y-252362D02*
X502362D01*
Y-257185D02*
Y-252362D01*
X504331Y-260136D02*
X506238D01*
X504331D02*
Y-257185D01*
X209449Y4195D02*
Y7087D01*
X203839Y-1514D02*
X203937D01*
X214173Y-1711D02*
Y1181D01*
X209449Y-3543D02*
Y1317D01*
X209055Y-5512D02*
X214173D01*
Y-4589D01*
X203839Y-7480D02*
X209055D01*
X203839D02*
Y-4392D01*
X214173Y-79134D02*
Y-76242D01*
X204537Y-79380D02*
X205118D01*
X204537Y-73697D02*
X205045Y-74205D01*
X205541D02*
X205631Y-74295D01*
X206074Y-74410D02*
X209449D01*
X204537Y-73697D02*
Y-73561D01*
X205045Y-74205D02*
X205541D01*
X205631Y-74295D02*
X205960D01*
X206074Y-74410D01*
X209449Y-72047D02*
X214173D01*
Y-73364D02*
Y-72047D01*
X603357Y-79921D02*
Y-79858D01*
X595276Y-79921D02*
Y-79921D01*
X598425D01*
X608268Y-59842D02*
X609291D01*
X608268Y-70079D02*
X608405D01*
X238189Y-138976D02*
X238386Y-138779D01*
Y-131890D01*
X217405Y-134835D02*
X219563Y-132677D01*
X223031D01*
X217323Y-138189D02*
X217405D01*
X192126Y-111811D02*
X192520D01*
X158661Y-98415D02*
X161302Y-95774D01*
Y-95390D02*
X161417Y-95276D01*
X158661Y-98551D02*
Y-98415D01*
X161302Y-95774D02*
Y-95390D01*
X153150Y-99870D02*
X153973Y-100693D01*
X155418D01*
X156153Y-101429D02*
X158661D01*
X155418Y-100693D02*
X156153Y-101429D01*
X167554Y-104331D02*
X167948Y-103937D01*
X164961Y-104331D02*
X167554D01*
X167948Y-103937D02*
X168110D01*
X165839Y-99697D02*
X167513D01*
X167948Y-100132D02*
X168110D01*
X164961Y-98819D02*
X165839Y-99697D01*
X167513D02*
X167948Y-100132D01*
X167949Y-141142D02*
Y-138779D01*
X165587Y-136417D02*
X167949Y-138779D01*
X164012Y-133685D02*
X165201Y-134874D01*
Y-136031D02*
Y-134874D01*
X164012Y-133685D02*
Y-131299D01*
X165201Y-136031D02*
X165587Y-136417D01*
X163127Y-132185D02*
X164012Y-131299D01*
X159583Y-132185D02*
X163127D01*
X150233Y-127362D02*
X150395D01*
X150872Y-126886D01*
X159013D01*
X159720Y-126179D01*
Y-126143D01*
X160863Y-125000D01*
X155622Y-118602D02*
X158008D01*
X164773Y-114161D02*
X164800Y-114134D01*
X166730Y-117597D02*
X167055Y-117921D01*
X167682D02*
X168441Y-118681D01*
X164746Y-117597D02*
X166730D01*
X167055Y-117921D02*
X167682D01*
X168441Y-118760D02*
Y-118681D01*
X164746Y-117597D02*
X164773Y-117570D01*
X160075Y-112564D02*
X161596Y-114085D01*
Y-117597D02*
Y-114085D01*
X160075Y-112564D02*
Y-112402D01*
X168264Y-110748D02*
X168343Y-110827D01*
X168392Y-110876D01*
Y-115246D02*
X168441Y-115295D01*
X168392Y-115246D02*
Y-110876D01*
X151808Y-137205D02*
X154957D01*
X56496Y-5709D02*
X56693D01*
X52362Y-35531D02*
X56824D01*
Y-31594D02*
Y-27362D01*
X56595D02*
X56824D01*
X61417Y-35741D02*
Y-27362D01*
X60335D02*
X61417D01*
X37402Y-43355D02*
X43268D01*
X38382Y-48355D02*
X43268D01*
X72795Y-53355D02*
Y-53218D01*
X64528Y-54241D02*
Y-53218D01*
X85827Y-16929D02*
X89484D01*
X85853Y-13129D02*
X89583D01*
X85853Y-13780D02*
Y-13129D01*
X112106Y-30315D02*
Y-25591D01*
X111024D02*
X112106D01*
X116929Y-21654D02*
Y-21654D01*
X111024Y-21654D02*
X116929D01*
X114829Y-16142D02*
X118898D01*
Y-16929D02*
Y-16142D01*
X383201Y-141339D02*
X384224D01*
X378083D02*
X383201D01*
X378083Y-153937D02*
Y-141339D01*
X383083Y-135039D02*
X383201D01*
X382036Y-232972D02*
X383315Y-234252D01*
X379392Y-232972D02*
X382036D01*
X383315Y-234252D02*
X383465D01*
X373093Y-232972D02*
X376514D01*
X615762Y-302756D02*
X619148D01*
X18110Y-296161D02*
X23524D01*
Y-294882D01*
X14173Y-296161D02*
X18110D01*
X14173D02*
Y-294320D01*
D19*
X589370Y-255869D02*
G03*
X590170Y-256668I800J0D01*
G01*
X590170Y-258268D02*
G03*
X590170Y-256668I0J800D01*
G01*
X590070Y-258268D02*
G03*
X590070Y-259869I0J-800D01*
G01*
X590377Y-261469D02*
G03*
X590377Y-259869I0J800D01*
G01*
X590170Y-261469D02*
G03*
X589370Y-262268I0J-800D01*
G01*
Y-255869D02*
Y-248141D01*
X590170Y-256668D02*
X590170D01*
X590070Y-258268D02*
X590170D01*
X590070Y-259869D02*
X590377D01*
X590170Y-261469D02*
X590377D01*
X589370Y-264169D02*
Y-262268D01*
Y-248141D02*
Y-246749D01*
Y-268898D02*
Y-264169D01*
X588170Y-269395D02*
Y-246393D01*
X596865Y-266667D02*
Y-266396D01*
X596415Y-269062D02*
Y-267117D01*
X596865Y-266667D01*
X593804Y-271672D02*
X596415Y-269062D01*
X588170Y-269395D02*
X590448Y-271672D01*
X593804D01*
X595215Y-268565D02*
Y-267117D01*
X594765Y-266667D02*
Y-266396D01*
Y-266667D02*
X595215Y-267117D01*
X593307Y-270472D02*
X595215Y-268565D01*
X590945Y-270472D02*
X593307D01*
X589370Y-268898D02*
X590945Y-270472D01*
X595792Y-239895D02*
X596063D01*
X594792Y-240895D02*
X595792Y-239895D01*
X594124Y-241995D02*
X596063D01*
X589370Y-246749D02*
X594124Y-241995D01*
X593668Y-240895D02*
X594792D01*
X588170Y-246393D02*
X593668Y-240895D01*
X596319Y-239973D02*
X600263D01*
X601181Y-239054D01*
X596319Y-242073D02*
X600263D01*
X601181Y-242991D01*
D25*
X522047Y-284252D02*
Y-270866D01*
Y-284252D02*
X522835Y-285039D01*
X77165Y-34252D02*
X83203Y-28215D01*
X100000Y-13780D02*
X107087Y-6693D01*
X83203Y-28215D02*
X94226D01*
X100000Y-22441D02*
Y-13780D01*
X94226Y-28215D02*
X100000Y-22441D01*
X519291Y-157480D02*
Y-90945D01*
X530709Y-79528D02*
Y-38976D01*
X519291Y-90945D02*
X530709Y-79528D01*
X527559Y-79263D02*
Y-38976D01*
X516535Y-153543D02*
Y-90287D01*
X527559Y-79263D01*
X169685Y-107480D02*
X177953Y-115748D01*
Y-126700D02*
X181335Y-130082D01*
X177953Y-126700D02*
Y-115748D01*
X522872Y-285077D02*
X530609Y-292814D01*
X564292Y-250513D02*
X580590D01*
X501162Y-233354D02*
X547133D01*
X564292Y-250513D01*
X499606Y-244882D02*
Y-244794D01*
X500119Y-244281D01*
Y-234397D01*
X501162Y-233354D01*
X480709Y-247638D02*
X496850D01*
X499606Y-244882D01*
X500787Y-231890D02*
X548032D01*
X482739Y-246125D02*
X494033D01*
X498819Y-243743D02*
Y-233858D01*
X500787Y-231890D01*
X494033Y-246125D02*
X494363Y-245795D01*
X496767D01*
X498819Y-243743D01*
X545669Y-280030D02*
Y-276378D01*
Y-285334D02*
Y-280030D01*
X533956Y-286712D02*
X544291D01*
X532677Y-285433D02*
X533956Y-286712D01*
X532677Y-285433D02*
Y-282892D01*
X532266Y-282481D02*
X532677Y-282892D01*
X544291Y-286712D02*
X545669Y-285334D01*
X536772Y-275669D02*
X544961D01*
X545669Y-276378D01*
X530984Y-281199D02*
Y-277638D01*
Y-281199D02*
X532266Y-282481D01*
X613355Y-248691D02*
X614822Y-250158D01*
X612867Y-248691D02*
X613355D01*
X611553Y-247377D02*
X612867Y-248691D01*
X530609Y-292814D02*
X547145D01*
X551968Y-297638D01*
X501958Y-187561D02*
X576454Y-113064D01*
X441234Y-187561D02*
X501958D01*
X576454Y-113064D02*
X580506D01*
X150108Y-138055D02*
Y-135184D01*
X150241Y-140004D02*
X150394Y-140157D01*
X150108Y-138055D02*
X150241Y-138188D01*
Y-140004D02*
Y-138188D01*
X150108Y-135184D02*
X153107Y-132185D01*
X172674Y-147011D02*
Y-138386D01*
X168898Y-150787D02*
X172674Y-147011D01*
X135827Y-150787D02*
X168898D01*
X124016Y-138976D02*
X135827Y-150787D01*
X124484Y-134130D02*
X126618D01*
X124016Y-134599D02*
X124484Y-134130D01*
X124016Y-138976D02*
Y-134599D01*
X129063Y-136618D02*
Y-136576D01*
X126618Y-134130D02*
X129063Y-136576D01*
X170311Y-145898D02*
Y-139961D01*
X166997Y-149213D02*
X170311Y-145898D01*
X139254Y-149213D02*
X166997D01*
X126307Y-136266D02*
X139254Y-149213D01*
X126307Y-136266D02*
Y-136224D01*
X328615Y-124045D02*
Y-119366D01*
X328146Y-118898D02*
X328615Y-119366D01*
X325197Y-118898D02*
X328146D01*
X321260Y-114961D02*
X325197Y-118898D01*
X328615Y-124045D02*
X336221Y-131651D01*
Y-151181D02*
Y-131651D01*
X345808Y-169076D02*
Y-160769D01*
X345669Y-169215D02*
X345808Y-169076D01*
X336221Y-151181D02*
X345808Y-160769D01*
X345669Y-169903D02*
Y-169215D01*
X341993Y-173579D02*
X345669Y-169903D01*
X325994Y-173579D02*
X341993D01*
X322938Y-176635D02*
X325994Y-173579D01*
X322938Y-187593D02*
Y-176635D01*
Y-187593D02*
X327165Y-191821D01*
Y-207669D02*
Y-191821D01*
X320536Y-214298D02*
X327165Y-207669D01*
X311936Y-214298D02*
X320536D01*
X309449Y-211811D02*
X311936Y-214298D01*
X327165Y-124803D02*
Y-120941D01*
X326697Y-120472D02*
X327165Y-120941D01*
X322835Y-120472D02*
X326697D01*
X317323Y-114961D02*
X322835Y-120472D01*
X334252Y-151246D02*
Y-131890D01*
X327165Y-124803D02*
X334252Y-131890D01*
X344443Y-168602D02*
Y-167735D01*
X344508Y-167671D01*
Y-161502D01*
X334252Y-151246D02*
X344508Y-161502D01*
X341173Y-171872D02*
X344443Y-168602D01*
X325313Y-171872D02*
X341173D01*
X318773Y-178413D02*
X325313Y-171872D01*
X318773Y-189494D02*
X324803Y-195524D01*
X318773Y-189494D02*
Y-178413D01*
X317323Y-208661D02*
X324335D01*
X324803Y-208193D01*
Y-195524D01*
X313386Y-212598D02*
X317323Y-208661D01*
X245276Y-115748D02*
Y-103807D01*
X243426Y-101957D02*
X245276Y-103807D01*
X243415Y-101969D02*
X243426Y-101957D01*
X219685Y-101969D02*
X243415D01*
X211648Y-103695D02*
X217959D01*
X219685Y-101969D01*
X194880Y-97638D02*
X197638D01*
X194412Y-98106D02*
X194880Y-97638D01*
X194412Y-102045D02*
Y-98106D01*
X193307Y-103150D02*
X194412Y-102045D01*
X184843Y-103150D02*
X193307D01*
X164567Y-90158D02*
X177559Y-103150D01*
X184843D02*
Y-99803D01*
X177559Y-103150D02*
X184843D01*
X-23622Y-110236D02*
X20030D01*
X52506Y-142711D01*
X17932Y-106299D02*
X53044Y-141411D01*
X-23622Y-106299D02*
X17932D01*
X-23622Y-102362D02*
X15834D01*
X53583Y-140111D01*
X-23622Y-66929D02*
X8661D01*
X74803Y-137937D02*
Y-133071D01*
Y-137937D02*
X78123Y-141257D01*
X81748D01*
X8661Y-66929D02*
X74803Y-133071D01*
X-23622Y-62992D02*
X7874D01*
X76772Y-131890D01*
Y-138067D02*
Y-131890D01*
Y-138067D02*
X78340Y-139636D01*
X80966D01*
X81044Y-139557D01*
X-23622Y-60039D02*
X7677D01*
X79044Y-137936D02*
Y-131407D01*
X7677Y-60039D02*
X79044Y-131407D01*
X19498Y-274990D02*
X107938D01*
X-23622Y-282480D02*
X-19882Y-286221D01*
X394D01*
X3937Y-282677D02*
X11811D01*
X394Y-286221D02*
X3937Y-282677D01*
X11811D02*
X19498Y-274990D01*
X23041Y-276959D02*
X109513D01*
X-23622Y-286417D02*
X-20620Y-289419D01*
X787D01*
X3593Y-286614D01*
X13386D01*
X23041Y-276959D01*
X-23622Y-290354D02*
X-20079Y-293898D01*
X2756D01*
X7677Y-288976D01*
X25951D01*
X35606Y-279321D02*
X111088D01*
X25951Y-288976D02*
X35606Y-279321D01*
X52913Y-283258D02*
X113131D01*
X-23622Y-335630D02*
X-8258D01*
X-7274Y-336614D01*
X7874D01*
X12324Y-332165D02*
X19804D01*
X7874Y-336614D02*
X12324Y-332165D01*
X27559Y-324409D02*
Y-310236D01*
X19804Y-332165D02*
X27559Y-324409D01*
Y-310236D02*
X45276Y-292520D01*
Y-290161D01*
X51805Y-284367D02*
X52913Y-283258D01*
X51070Y-284367D02*
X51805D01*
X45276Y-290161D02*
X51070Y-284367D01*
X51261Y-286014D02*
X114706D01*
X25197Y-333465D02*
X30315Y-328346D01*
X16929Y-333465D02*
X25197D01*
X30315Y-328346D02*
Y-314173D01*
X51261Y-293227D02*
Y-286014D01*
X30315Y-314173D02*
X51261Y-293227D01*
X-23622Y-339567D02*
X10827D01*
X16929Y-333465D01*
X-8947Y-342520D02*
X-8160Y-341732D01*
X6299D01*
X60920Y-288376D02*
X114182D01*
X-23622Y-342520D02*
X-8947D01*
X27295Y-342498D02*
Y-341209D01*
X26826Y-342966D02*
X27295Y-342498D01*
X7533Y-342966D02*
X26826D01*
X6299Y-341732D02*
X7533Y-342966D01*
X27295Y-341209D02*
X37795Y-330709D01*
Y-311501D02*
X60920Y-288376D01*
X37795Y-330709D02*
Y-311501D01*
X105532Y-200000D02*
Y-120340D01*
X100729Y-119871D02*
X105063D01*
X105532Y-120340D01*
X103170Y-202362D02*
X105532Y-200000D01*
X26772Y-202362D02*
X103170D01*
X7283Y-229331D02*
X9843Y-226772D01*
X-23622Y-229331D02*
X7283D01*
X9843Y-226772D02*
Y-207290D01*
X18520Y-198612D02*
X104076D01*
X9843Y-207290D02*
X18520Y-198612D01*
X-23622Y-233268D02*
X11427D01*
X14379Y-230315D01*
Y-214755D01*
X26772Y-202362D01*
X24214Y-207667D02*
X106363D01*
X-23622Y-237205D02*
X-19882Y-240945D01*
X14567D01*
X24214Y-231298D02*
Y-207667D01*
X14567Y-240945D02*
X24214Y-231298D01*
X100729Y-171318D02*
Y-127872D01*
X100394Y-171653D02*
X100729Y-171318D01*
X99299Y-179440D02*
X100394Y-178346D01*
Y-171653D01*
X31015Y-179440D02*
X99299D01*
X30451Y-178876D02*
X31015Y-179440D01*
X-23622Y-181102D02*
X657D01*
X10060Y-171700D01*
Y-153631D01*
X12205Y-151487D01*
X29686D01*
X30451Y-178876D02*
Y-152252D01*
X29686Y-151487D02*
X30451Y-152252D01*
X8760Y-150187D02*
X31877D01*
X-23622Y-177165D02*
X-22047Y-175591D01*
X4331D01*
X8760Y-171161D02*
Y-150187D01*
X4331Y-175591D02*
X8760Y-171161D01*
X13345Y-152790D02*
X29151D01*
X-23622Y-184055D02*
X1326D01*
X13345Y-172037D02*
Y-152790D01*
X1326Y-184055D02*
X13345Y-172037D01*
X81748Y-141257D02*
X83044Y-139961D01*
Y-137936D01*
X84448Y-142557D02*
X87044Y-139961D01*
X84987Y-143857D02*
X87433Y-141411D01*
X87044Y-139961D02*
Y-137936D01*
X87433Y-141411D02*
X88576D01*
X89044Y-140943D01*
Y-139557D01*
X90080Y-142711D02*
X91044Y-141747D01*
Y-137936D01*
X98761Y-178140D02*
Y-129872D01*
X53044Y-141411D02*
X72413D01*
X53583Y-140111D02*
X73329D01*
X72413Y-141411D02*
X74859Y-143857D01*
X73329Y-140111D02*
X75774Y-142557D01*
X98761Y-125872D02*
X102501D01*
X98761Y-121871D02*
X104076D01*
X98761Y-117746D02*
X106363D01*
X81150Y-108730D02*
X81400Y-108479D01*
X80981Y-108730D02*
Y-108061D01*
Y-108730D02*
X81150D01*
X86981Y-110029D02*
Y-105699D01*
X82918Y-110029D02*
Y-104518D01*
X78918Y-110029D02*
Y-101837D01*
X80981Y-108061D02*
Y-103099D01*
X82918Y-104518D02*
X86324D01*
X86443Y-104399D01*
X97895Y-109836D02*
X98364Y-110304D01*
X91044Y-115680D02*
X107938D01*
X93409Y-113911D02*
X93878Y-114380D01*
X91044Y-115680D02*
Y-110061D01*
X95021Y-112611D02*
X95489Y-113080D01*
X96596Y-111136D02*
X97064Y-111604D01*
X93409Y-113911D02*
Y-108061D01*
X95021Y-112611D02*
Y-105699D01*
X88981Y-108061D02*
X93409D01*
X88981D02*
Y-108061D01*
X96596Y-111136D02*
Y-104518D01*
X97895Y-109836D02*
Y-103979D01*
X86981Y-105699D02*
X95021D01*
X95678Y-104518D02*
X96596D01*
X95559Y-104399D02*
X95678Y-104518D01*
X86443Y-104399D02*
X95559D01*
X97015Y-103099D02*
X97895Y-103979D01*
X80981Y-103099D02*
X97015D01*
X97123Y-101368D02*
X99745Y-103990D01*
X93878Y-114380D02*
X108476D01*
X95489Y-113080D02*
X110595D01*
X97064Y-111604D02*
X112662D01*
X98364Y-110304D02*
X114118D01*
X99745Y-108380D02*
X100370Y-109004D01*
X99745Y-108380D02*
Y-103990D01*
X308979Y-159132D02*
X315700D01*
X317828Y-161260D01*
X305118Y-162992D02*
X308979Y-159132D01*
X309562Y-164018D02*
X311457D01*
X313878Y-161597D01*
X246850Y-153543D02*
X270866Y-177559D01*
X326204Y-166966D02*
X342808D01*
X270866Y-177559D02*
X298578D01*
X302900Y-181882D01*
Y-198084D02*
Y-181882D01*
X306349Y-201533D02*
X316013D01*
X316535Y-201010D01*
X302900Y-198084D02*
X306349Y-201533D01*
X316535Y-201010D02*
Y-176635D01*
X326204Y-166966D01*
X246850Y-153543D02*
Y-129921D01*
X513386Y-199213D02*
X521043D01*
X314862Y-243419D02*
Y-239469D01*
X321654Y-232677D01*
X427658Y-137992D02*
Y-132677D01*
X438655Y-209968D02*
X441119D01*
X389567Y-196440D02*
X393660Y-200532D01*
X438655Y-223747D02*
Y-209968D01*
X434895Y-227506D02*
X438655Y-223747D01*
X416851Y-227506D02*
X434895D01*
X411392Y-222047D02*
X416851Y-227506D01*
X404584Y-222047D02*
X411392D01*
X402362Y-219825D02*
X404584Y-222047D01*
X402362Y-219825D02*
Y-216647D01*
X393660Y-207945D02*
X402362Y-216647D01*
X393660Y-207945D02*
Y-200532D01*
X386221Y-200735D02*
X388583Y-203098D01*
Y-210936D02*
Y-203098D01*
Y-210936D02*
X411505Y-233858D01*
X427165D01*
X386221Y-200735D02*
Y-193307D01*
X142471Y-55069D02*
X152756Y-65354D01*
X142471Y-55069D02*
Y-38353D01*
X152707Y-57529D02*
X152756Y-57480D01*
X148080Y-57529D02*
X152707D01*
X380328Y-203924D02*
X382677Y-201575D01*
X380328Y-225603D02*
Y-203924D01*
Y-225603D02*
X383372Y-228647D01*
X381890Y-188451D02*
Y-183858D01*
X381416Y-193301D02*
Y-188925D01*
X381890Y-188451D01*
X454775Y-308565D02*
X454865Y-308476D01*
X460402D01*
X463363Y-311437D01*
Y-343284D02*
Y-311437D01*
Y-343284D02*
X468110Y-348031D01*
X509842D01*
X521654Y-336221D01*
X548094Y-298363D02*
X549515D01*
X551056Y-307630D02*
Y-299904D01*
X549515Y-298363D02*
X551056Y-299904D01*
X541339Y-305118D02*
X548094Y-298363D01*
X505512Y-306693D02*
X507480D01*
X541339Y-313792D02*
Y-305118D01*
X517204Y-316417D02*
X538714D01*
X541339Y-313792D01*
X507480Y-306693D02*
X517204Y-316417D01*
X491535Y-312205D02*
X510802D01*
X540158Y-317717D02*
X544882Y-312992D01*
Y-305118D01*
X516314Y-317717D02*
X540158D01*
X510802Y-312205D02*
X516314Y-317717D01*
X435982Y-165986D02*
Y-162861D01*
X438796Y-160047D02*
X475882D01*
X476071Y-160236D02*
X509842D01*
X475882Y-160047D02*
X476071Y-160236D01*
X435982Y-162861D02*
X438796Y-160047D01*
X509842Y-160236D02*
X516535Y-153543D01*
X417792Y-172441D02*
X443346D01*
X507480Y-169291D02*
X519291Y-157480D01*
X446495Y-169291D02*
X507480D01*
X443346Y-172441D02*
X446495Y-169291D01*
X579968Y-111764D02*
X601745Y-89987D01*
X602283Y-91287D02*
X604645D01*
X601745Y-89987D02*
X604107D01*
X575916Y-111764D02*
X579968D01*
X580506Y-113064D02*
X602283Y-91287D01*
X441772Y-186261D02*
X501419D01*
X575916Y-111764D01*
X421313Y-175184D02*
X430696D01*
X606616Y-87478D02*
Y-85903D01*
X604107Y-89987D02*
X606616Y-87478D01*
X608268Y-84252D02*
X610613Y-86598D01*
X612913D02*
X615354Y-89039D01*
X610613Y-86598D02*
X612913D01*
X606616Y-85903D02*
X608268Y-84252D01*
X615354Y-90551D02*
Y-89039D01*
X611811Y-94095D02*
X615354Y-90551D01*
X604311Y-94095D02*
X611811D01*
X600405Y-98001D02*
X604311Y-94095D01*
X586397Y-116623D02*
X600405Y-102615D01*
Y-98001D01*
X586397Y-121477D02*
Y-116623D01*
X430696Y-175184D02*
X441772Y-186261D01*
X500787Y-207087D02*
X586397Y-121477D01*
X421313Y-175184D02*
Y-174784D01*
X447678Y-207087D02*
X500787D01*
X442089Y-212675D02*
X447678Y-207087D01*
X433415Y-237008D02*
X442089Y-228334D01*
Y-212675D01*
X421772Y-237008D02*
X433415D01*
X417835Y-240945D02*
X421772Y-237008D01*
X404354Y-255237D02*
X417835Y-241756D01*
Y-240945D01*
X398813Y-253043D02*
Y-250978D01*
X396850Y-249016D02*
X398813Y-250978D01*
X401007Y-255237D02*
X404354D01*
X398813Y-253043D02*
X401007Y-255237D01*
X604645Y-91287D02*
X606439Y-89494D01*
X613406D01*
X603773Y-92795D02*
X610105D01*
X599105Y-102076D02*
Y-97462D01*
X603773Y-92795D01*
X610105D02*
X613406Y-89494D01*
X585097Y-116085D02*
X599105Y-102076D01*
X585097Y-120939D02*
Y-116085D01*
X420019Y-176484D02*
X430158D01*
X419828Y-176715D02*
Y-176675D01*
X500249Y-205787D02*
X585097Y-120939D01*
X430158Y-176484D02*
X441234Y-187561D01*
X419828Y-176675D02*
X420019Y-176484D01*
X419798Y-176745D02*
X419828Y-176715D01*
X447139Y-205787D02*
X500249D01*
X440789Y-227796D02*
Y-212137D01*
X447139Y-205787D01*
X421234Y-235708D02*
X432877D01*
X440789Y-227796D01*
X416535Y-240406D02*
X421234Y-235708D01*
X416535Y-241217D02*
Y-240406D01*
X403816Y-253937D02*
X416535Y-241217D01*
X401545Y-253937D02*
X403816D01*
X400113Y-250675D02*
X401575Y-249213D01*
X400113Y-252504D02*
X401545Y-253937D01*
X400113Y-252504D02*
Y-250675D01*
X490945Y-197638D02*
Y-191335D01*
X490476Y-190866D02*
X490945Y-191335D01*
X438110Y-190866D02*
X490476D01*
X225590Y-49213D02*
X271260Y-3543D01*
X527559Y-38976D02*
X529921Y-36614D01*
Y5118D01*
X518898Y16142D02*
X529921Y5118D01*
X390158Y16142D02*
X518898D01*
X370472Y-3543D02*
X390158Y16142D01*
X271260Y-3543D02*
X370472D01*
X223436Y-22441D02*
X238349D01*
X530709Y-38976D02*
X534646Y-35039D01*
Y8661D01*
X523228Y20079D02*
X534646Y8661D01*
X280868Y20079D02*
X523228D01*
X238349Y-22441D02*
X280868Y20079D01*
X417323Y-180026D02*
Y-172910D01*
X417792Y-172441D01*
X386221Y-193307D02*
X409449Y-170079D01*
X431890D01*
X435982Y-165986D01*
X59016Y-58729D02*
X64528D01*
X153107Y-132185D02*
X156434D01*
X223223Y-103543D02*
X239370D01*
X241082Y-105255D01*
Y-108525D02*
Y-105255D01*
X238583Y-111024D02*
X241082Y-108525D01*
X238583Y-121653D02*
Y-111024D01*
Y-121653D02*
X246850Y-129921D01*
X427165Y-233858D02*
X429528Y-231496D01*
X332227Y-310236D02*
X444677D01*
X324184Y-302194D02*
X332227Y-310236D01*
X444677D02*
X446539Y-312099D01*
X210480Y-49213D02*
X225590D01*
X213707Y-29134D02*
X216743D01*
X223436Y-22441D01*
X429160Y-205309D02*
X431161D01*
X432237Y-204232D01*
X427953Y-206299D02*
X428169D01*
X429160Y-205309D01*
X469909Y-197244D02*
X481496D01*
X464643Y-202510D02*
X469909Y-197244D01*
X446211Y-202510D02*
X464643D01*
X446601Y-204487D02*
X484096D01*
X490945Y-197638D01*
X71260Y-75984D02*
Y-61417D01*
Y-75984D02*
X82284Y-87008D01*
X107874D01*
X113348Y-81534D01*
X317323Y-264764D02*
X334842Y-247244D01*
X317323Y-283071D02*
Y-264764D01*
X310630Y-289764D02*
X317323Y-283071D01*
X310630Y-302756D02*
Y-289764D01*
X309842Y-303543D02*
X310630Y-302756D01*
X258661Y-303543D02*
X309842D01*
X218823Y-343382D02*
X258661Y-303543D01*
X207161Y-343382D02*
X218823D01*
X198031Y-334252D02*
X207161Y-343382D01*
X338583Y-244801D02*
Y-235039D01*
X308268Y-270866D02*
X325434Y-253700D01*
X304921Y-270866D02*
X308268D01*
X325434Y-253700D02*
Y-250157D01*
X330789Y-244801D01*
X338583D01*
X289757Y-256299D02*
X319199D01*
X334646Y-243307D02*
X337008Y-240945D01*
X319199Y-256299D02*
X322441Y-253058D01*
Y-245276D01*
X324409Y-243307D01*
X334646D01*
X209842Y-334252D02*
X225197D01*
X231102Y-328346D01*
Y-307480D01*
X238314Y-300269D01*
Y-288389D01*
X238783Y-287920D02*
X256869D01*
X238314Y-288389D02*
X238783Y-287920D01*
X256994Y-287795D02*
X270866D01*
X256869Y-287920D02*
X256994Y-287795D01*
X270866D02*
X278346Y-280315D01*
X295472D01*
X304921Y-270866D01*
X338583Y-235039D02*
X340916Y-232706D01*
X345418D01*
X357480Y-220644D01*
Y-214567D01*
X329134Y-228740D02*
X337008Y-236614D01*
Y-240945D02*
Y-236614D01*
X275978Y-270079D02*
X289757Y-256299D01*
X242126Y-270079D02*
X275978D01*
X236614Y-275590D02*
X242126Y-270079D01*
X206299Y-275590D02*
X236614D01*
X180646Y-301243D02*
X206299Y-275590D01*
X180646Y-328678D02*
Y-301243D01*
Y-328678D02*
X186221Y-334252D01*
X182283Y-97244D02*
X184843Y-99803D01*
X462473Y-291017D02*
X466142Y-294685D01*
X462473Y-291017D02*
Y-277635D01*
X410236Y-262205D02*
X418898Y-253543D01*
Y-245276D01*
X398031Y-262205D02*
X410236D01*
X393701Y-257874D02*
X398031Y-262205D01*
X393701Y-257874D02*
Y-229116D01*
X393232Y-228647D02*
X393701Y-229116D01*
X383372Y-228647D02*
X393232D01*
X382677Y-201575D02*
Y-194563D01*
X381416Y-193301D02*
X382677Y-194563D01*
X131971Y-3031D02*
X137914D01*
X141339Y394D01*
X107087Y-6693D02*
X128308D01*
X131971Y-3031D01*
X77165Y-55512D02*
Y-34252D01*
X71260Y-61417D02*
X77165Y-55512D01*
X113348Y-81534D02*
X137046D01*
X142126Y-86614D01*
X144488D01*
X148031Y-90158D01*
X164567D01*
X476378Y-282583D02*
Y-273622D01*
X475072Y-283889D02*
X476378Y-282583D01*
X475072Y-306618D02*
Y-283889D01*
X482864Y-307087D02*
X484663Y-305287D01*
X496625D02*
X498425Y-307087D01*
X484663Y-305287D02*
X496625D01*
X475540Y-307087D02*
X482864D01*
X470079D02*
X475540D01*
X465748Y-302756D02*
X470079Y-307087D01*
X461024Y-302756D02*
X465748D01*
X484252Y-269291D02*
X510719Y-295758D01*
X472047Y-269291D02*
X484252D01*
X510719Y-300215D02*
Y-295758D01*
X462527Y-259771D02*
X472047Y-269291D01*
X383071Y-276772D02*
X387008Y-280709D01*
X398425D01*
X430315Y-248819D01*
X452756D01*
X458780Y-242794D01*
X479409D01*
X482739Y-246125D01*
X548032Y-231890D02*
X565354Y-249213D01*
X579718D01*
X594215Y-234716D02*
Y-229801D01*
X579718Y-249213D02*
X594215Y-234716D01*
Y-229801D02*
X606693Y-217323D01*
X610630D01*
X611811Y-218504D01*
Y-221260D02*
Y-218504D01*
X606818Y-224284D02*
X618796D01*
X580590Y-250513D02*
X606818Y-224284D01*
X468504Y-244094D02*
X477165D01*
X431496Y-252362D02*
X462368D01*
X477165Y-244094D02*
X480709Y-247638D01*
X466388Y-246211D02*
X468504Y-244094D01*
X466388Y-248343D02*
Y-246211D01*
X462368Y-252362D02*
X466388Y-248343D01*
X402756Y-281102D02*
X431496Y-252362D01*
X622858Y-228346D02*
X626987D01*
X618796Y-224284D02*
X622858Y-228346D01*
X269952Y-189891D02*
X275590Y-184252D01*
X256907Y-201360D02*
X268377Y-189891D01*
X269952D01*
X162221Y-334252D02*
Y-302346D01*
X239764Y-252756D02*
Y-246457D01*
X230709Y-261811D02*
X239764Y-252756D01*
X162221Y-302346D02*
X202756Y-261811D01*
X230709D01*
X239764Y-246457D02*
X256907Y-229313D01*
Y-201360D01*
X294094Y-201181D02*
Y-194656D01*
X289370Y-205906D02*
X294094Y-201181D01*
X292815Y-193376D02*
X294094Y-194656D01*
X144488Y394D02*
Y11220D01*
X142520Y13189D02*
X144488Y11220D01*
X139764Y-4331D02*
X144488Y394D01*
X132677Y-4331D02*
X139764D01*
X122589Y-14419D02*
X132677Y-4331D01*
X122589Y-18398D02*
Y-14419D01*
X118012Y-28445D02*
Y-22975D01*
X117323Y-65354D02*
Y-56406D01*
X112795Y-51879D02*
Y-33661D01*
X118012Y-22975D02*
X122589Y-18398D01*
X112795Y-51879D02*
X117323Y-56406D01*
X112795Y-33661D02*
X118012Y-28445D01*
X148819Y1575D02*
Y10278D01*
X150684Y12143D01*
X140945Y-6299D02*
X148819Y1575D01*
X137598Y-6299D02*
X140945D01*
X187402Y-33071D02*
X194339D01*
X210480Y-49213D01*
X159547Y-10138D02*
X162598Y-13189D01*
X159547Y-10138D02*
Y-8343D01*
X166261Y-11930D02*
Y-9961D01*
X159547Y-8343D02*
X160410Y-7480D01*
X163779D01*
X166261Y-9961D01*
Y-11930D02*
X187402Y-33071D01*
X205507Y-121260D02*
X223223Y-103543D01*
X186614Y-121260D02*
X205507D01*
X185039Y-119685D02*
X186614Y-121260D01*
X185039Y-119685D02*
Y-116571D01*
X188028Y-113583D01*
X423727Y-180026D02*
X446211Y-202510D01*
X417323Y-180026D02*
X423727D01*
X441119Y-209968D02*
X446601Y-204487D01*
X426772Y-179528D02*
X438110Y-190866D01*
X164815Y-5906D02*
X168110Y-9201D01*
X151772Y-29053D02*
Y-9801D01*
X178740Y-21260D02*
X211024D01*
Y-26451D02*
X213707Y-29134D01*
X211024Y-26451D02*
Y-21260D01*
X168110Y-10630D02*
Y-9201D01*
X155667Y-5906D02*
X164815D01*
X142471Y-38353D02*
X151772Y-29053D01*
X168110Y-10630D02*
X178740Y-21260D01*
X151772Y-9801D02*
X155667Y-5906D01*
X183712Y-352161D02*
X198392Y-366842D01*
X187402Y-348031D02*
X202756Y-363386D01*
Y-368110D02*
Y-363386D01*
X200343Y-370523D02*
X202756Y-368110D01*
X196701Y-370523D02*
X200343D01*
X142126Y-348031D02*
X187402D01*
X141587Y-352161D02*
X183712D01*
X341371Y-283465D02*
X415748D01*
X321850D02*
X327435D01*
X330709Y-280191D01*
Y-260236D01*
X335039Y-255906D01*
X339370D01*
X341732Y-258268D01*
Y-261024D02*
Y-258268D01*
X339370Y-263386D02*
X341732Y-261024D01*
X339370Y-281464D02*
Y-263386D01*
Y-281464D02*
X341371Y-283465D01*
X445620Y-294220D02*
X462205Y-277635D01*
X426504Y-294220D02*
X445620D01*
X415748Y-283465D02*
X426504Y-294220D01*
X462205Y-277635D02*
X462473D01*
X483465Y-291535D02*
X498044D01*
Y-299225D02*
Y-291535D01*
Y-299225D02*
X505512Y-306693D01*
X549213Y-335433D02*
Y-322047D01*
X552837Y-318423D01*
X540551Y-340945D02*
X543701D01*
X549213Y-335433D01*
X551056Y-307630D02*
X552837Y-309412D01*
Y-318423D02*
Y-309412D01*
X465354Y-319291D02*
X465444Y-319202D01*
X540551Y-348031D02*
X552756Y-335827D01*
X524803Y-338970D02*
Y-331177D01*
X457480Y-306662D02*
Y-299606D01*
X465354Y-340551D02*
Y-319291D01*
X468376Y-343573D02*
X487923D01*
X465354Y-340551D02*
X468376Y-343573D01*
X457480Y-299606D02*
X458858Y-298228D01*
X465444Y-319202D02*
Y-311549D01*
X500787Y-330709D02*
X524334D01*
X528576Y-348031D02*
X540551D01*
X524803Y-338970D02*
X528576Y-342742D01*
X458858Y-298228D02*
X466142D01*
X528576Y-348031D02*
Y-342742D01*
X487923Y-343573D02*
X500787Y-330709D01*
X460557Y-306662D02*
X465444Y-311549D01*
X524334Y-330709D02*
X524803Y-331177D01*
X457480Y-306662D02*
X460557D01*
X544882Y-336221D02*
Y-325984D01*
X543387Y-324490D02*
X544882Y-325984D01*
X491419Y-324490D02*
X543387D01*
X487008Y-320079D02*
X491419Y-324490D01*
X548819Y-312196D02*
Y-300787D01*
X496230Y-317883D02*
X500910Y-322563D01*
X484842Y-317717D02*
X496230D01*
X547047Y-322563D02*
X547515Y-322095D01*
X496230Y-317883D02*
Y-317717D01*
X547515Y-322095D02*
Y-313499D01*
X548819Y-312196D01*
X500910Y-322563D02*
X547047D01*
X478853Y-315467D02*
X483465Y-320079D01*
X473819Y-315354D02*
X473932Y-315467D01*
X478853D01*
X483465Y-320079D02*
X487008D01*
X489567Y-310236D02*
X491535Y-312205D01*
X491549Y-219896D02*
X500971D01*
X488189Y-216535D02*
X491549Y-219896D01*
X418898Y-245276D02*
X424803Y-239370D01*
X485827D01*
X446539Y-312099D02*
X461417D01*
X539764Y-358661D02*
X542126Y-356299D01*
X567573Y-351969D02*
X589764D01*
X556693Y-356299D02*
X558268Y-357874D01*
X594488Y-347244D02*
X620079D01*
X493234Y-356620D02*
X525920D01*
X620079Y-347244D02*
X624016Y-343307D01*
X567573Y-352261D02*
Y-351969D01*
X525920Y-356620D02*
X527962Y-358661D01*
X539764D01*
X558268Y-357874D02*
X561960D01*
X567573Y-352261D01*
X542126Y-356299D02*
X556693D01*
X589764Y-351969D02*
X594488Y-347244D01*
X312005Y-241084D02*
Y-239373D01*
X353937Y-210894D02*
Y-190310D01*
X312005Y-239373D02*
X324338Y-227040D01*
X337790D01*
X309782Y-243307D02*
X312005Y-241084D01*
X341732Y-181102D02*
X346457Y-185827D01*
X337790Y-227040D02*
X353937Y-210894D01*
X337795Y-181102D02*
X341732D01*
X346457Y-185827D02*
X349453D01*
X353937Y-190310D01*
X312322Y-236221D02*
X323346Y-225197D01*
X334252Y-185101D02*
X336386Y-187234D01*
X323346Y-225197D02*
X337795D01*
X342789Y-187234D02*
X351791Y-196236D01*
X334252Y-185101D02*
Y-180315D01*
X337795Y-225197D02*
X351791Y-211201D01*
X336386Y-187234D02*
X342789D01*
X351791Y-211201D02*
Y-196236D01*
X240158Y-278740D02*
X240231D01*
X240700Y-279648D02*
Y-279209D01*
Y-279648D02*
X241169Y-280116D01*
X274542D02*
X280382Y-274277D01*
X240231Y-278740D02*
X240700Y-279209D01*
X241169Y-280116D02*
X274542D01*
X161417Y-25984D02*
Y-18307D01*
X153543Y-10433D02*
X161417Y-18307D01*
X153408Y-30709D02*
X162598D01*
X143925Y-53374D02*
Y-40192D01*
X153408Y-30709D01*
X143925Y-53374D02*
X148080Y-57529D01*
X164961Y-28346D02*
Y-11811D01*
X162598Y-9449D02*
X164961Y-11811D01*
X162598Y-30709D02*
X164961Y-28346D01*
X218504Y-53150D02*
X224016Y-58661D01*
X210630Y-53150D02*
X218504D01*
X224016Y-75984D02*
Y-58661D01*
X197244Y-102756D02*
X224016Y-75984D01*
X179927Y-97292D02*
X181004Y-98369D01*
X203516Y-58689D02*
X209541D01*
X188189Y-74016D02*
X203516Y-58689D01*
X188189Y-86516D02*
Y-74016D01*
X179927Y-94777D02*
X188189Y-86516D01*
X179927Y-97292D02*
Y-94777D01*
X181004Y-101181D02*
Y-98369D01*
X155427Y-33907D02*
X170705D01*
X192113Y-55315D01*
X216339D02*
X218110Y-57087D01*
X192113Y-55315D02*
X216339D01*
X218110Y-64456D02*
Y-57087D01*
X205607Y-65102D02*
X217464D01*
X198524Y-72186D02*
X205607Y-65102D01*
X198524Y-87795D02*
Y-72186D01*
X217464Y-65102D02*
X218110Y-64456D01*
X139844Y-81970D02*
X142126Y-84252D01*
X114858Y-33771D02*
X117133Y-31496D01*
X114858Y-51660D02*
Y-33771D01*
X118898Y-58661D02*
Y-55700D01*
X120859Y-60623D02*
X131489D01*
X162926Y-84252D02*
X169226Y-90551D01*
X133691Y-73375D02*
Y-62825D01*
X118898Y-58661D02*
X120859Y-60623D01*
X177854Y-90551D02*
X180610Y-87795D01*
X139844Y-81970D02*
Y-79528D01*
X117133Y-31496D02*
X121653D01*
X142126Y-84252D02*
X162926D01*
X133691Y-73375D02*
X139844Y-79528D01*
X131489Y-60623D02*
X133691Y-62825D01*
X169226Y-90551D02*
X177854D01*
X114858Y-51660D02*
X118898Y-55700D01*
X123640Y-52603D02*
X127559Y-48684D01*
X145592Y-4362D02*
X164142D01*
X135827Y-33387D02*
Y-14127D01*
X159843Y9646D02*
X165354Y4134D01*
X121653Y-52756D02*
X121807Y-52603D01*
X127559Y-41655D02*
X135827Y-33387D01*
X121807Y-52603D02*
X123640D01*
X164142Y-4362D02*
X165354Y-3150D01*
X127559Y-48684D02*
Y-41655D01*
X135827Y-14127D02*
X145592Y-4362D01*
X165354Y-3150D02*
Y4134D01*
X121457Y-57529D02*
X144685Y-34301D01*
Y-11811D01*
X216535Y-25197D02*
X225984Y-15748D01*
X213583Y9646D02*
X225984Y-2756D01*
X169291Y9646D02*
X213583D01*
X225984Y-15748D02*
Y-2756D01*
X150684Y12143D02*
X162090D01*
X194488Y-16535D02*
X211811D01*
X176181Y1772D02*
X194488Y-16535D01*
X172461Y1772D02*
X176181D01*
X162090Y12143D02*
X172461Y1772D01*
X175197Y6693D02*
X193307Y-11417D01*
X214567D01*
X151181Y14173D02*
X162229D01*
X169709Y6693D01*
X175197D01*
X182165Y-162847D02*
X202362Y-142650D01*
X182165Y-232379D02*
Y-162847D01*
Y-232379D02*
X201074Y-251289D01*
Y-251861D02*
Y-251289D01*
Y-251861D02*
X203937Y-254724D01*
X202362Y-142650D02*
Y-141849D01*
X199193Y-138680D02*
X202362Y-141849D01*
X183465Y-163386D02*
X204193Y-142657D01*
X183465Y-231841D02*
Y-163386D01*
Y-231841D02*
X203805Y-252182D01*
X204193Y-142657D02*
Y-138257D01*
X272761Y-181890D02*
X296457D01*
X320868Y-203937D02*
X322835Y-201971D01*
Y-196063D01*
X301208Y-203937D02*
X320868D01*
X300739Y-203468D02*
Y-192153D01*
Y-203468D02*
X301208Y-203937D01*
X296457Y-187870D02*
X300739Y-192153D01*
X296457Y-187870D02*
Y-181890D01*
X238189Y-250000D02*
Y-245033D01*
X58268Y-323622D02*
Y-314567D01*
X254657Y-199994D02*
X272761Y-181890D01*
X229997Y-258192D02*
X238189Y-250000D01*
X72441Y-300394D02*
X144882D01*
X238189Y-245033D02*
X254657Y-228565D01*
X144882Y-300394D02*
X187084Y-258192D01*
X229997D01*
X58268Y-314567D02*
X72441Y-300394D01*
X254657Y-228565D02*
Y-199994D01*
X52506Y-142711D02*
X71590D01*
X87971D02*
X90080D01*
X85526Y-145157D02*
X87971Y-142711D01*
X71590D02*
X74036Y-145157D01*
X85526D01*
X74859Y-143857D02*
X84987D01*
X75774Y-142557D02*
X84448D01*
X79387Y-101368D02*
X97123D01*
X114657Y-109004D02*
X116281Y-110628D01*
X78918Y-101837D02*
X79387Y-101368D01*
X116281Y-286278D02*
Y-110628D01*
X100370Y-109004D02*
X114657D01*
X114182Y-288376D02*
X116281Y-286278D01*
X114118Y-110304D02*
X114706Y-110892D01*
Y-286014D02*
Y-110892D01*
X113131Y-283258D02*
Y-112073D01*
X112662Y-111604D02*
X113131Y-112073D01*
X111088Y-279321D02*
X111556Y-278852D01*
X110595Y-113080D02*
X111556Y-114041D01*
Y-278852D02*
Y-114041D01*
X108476Y-114380D02*
X109981Y-115885D01*
X109513Y-276959D02*
X109981Y-276490D01*
Y-115885D01*
X107938Y-115680D02*
X108406Y-116149D01*
X107938Y-274990D02*
X108406Y-274522D01*
Y-116149D01*
X106363Y-207667D02*
X106832Y-207199D01*
Y-118215D01*
X106363Y-117746D02*
X106832Y-118215D01*
X104076Y-198612D02*
Y-121871D01*
X29151Y-181289D02*
Y-152790D01*
X102501Y-181289D02*
Y-125872D01*
X29151Y-181289D02*
X102501D01*
X31877Y-178140D02*
Y-150187D01*
Y-178140D02*
X98761D01*
X608529Y-99109D02*
X609449Y-98189D01*
X602105Y-99109D02*
X608529D01*
X597397Y-108508D02*
X609129D01*
X597244Y-108661D02*
X597397Y-108508D01*
X609129D02*
X609449Y-108189D01*
X592913Y-116535D02*
X594567Y-118189D01*
X609449D01*
X594488Y-132677D02*
X604961D01*
X609449Y-128189D01*
X31398Y-23566D02*
Y-4331D01*
X42325Y-34493D02*
X43548D01*
X31398Y-23566D02*
X42325Y-34493D01*
X43548D02*
X43701Y-34646D01*
X34449Y16339D02*
X35433Y15354D01*
X31398Y16339D02*
X34449D01*
X35039Y9449D02*
X36220Y8268D01*
X31398Y9449D02*
X35039D01*
X35827Y1575D02*
Y1969D01*
X35236Y2559D02*
X35827Y1969D01*
X31398Y2559D02*
X35236D01*
X24908Y-2861D02*
X26083Y-4035D01*
X24613Y-2861D02*
X24908D01*
X19685Y-2362D02*
X24114D01*
X26083Y-4331D02*
Y-4035D01*
X24114Y-2362D02*
X24613Y-2861D01*
X24908Y3937D02*
X26083Y2762D01*
Y2559D02*
Y2762D01*
X20079Y3937D02*
X24908D01*
Y10630D02*
X26083Y9455D01*
Y9449D02*
Y9455D01*
X20079Y10630D02*
X24908D01*
X20079Y17323D02*
X25098D01*
X26083Y16339D01*
X287180Y-274277D02*
X287835Y-273622D01*
X280382Y-274277D02*
X287180D01*
X378937Y-265551D02*
Y-249803D01*
Y-265551D02*
X391339Y-277953D01*
X510719Y-300215D02*
X513406Y-302902D01*
X437330Y-259771D02*
X462527D01*
X432283Y-254724D02*
X437330Y-259771D01*
X485827Y-239370D02*
X490551Y-244094D01*
X496063D01*
X305118Y-191732D02*
Y-162992D01*
Y-191732D02*
X309055Y-195669D01*
X307493Y-187415D02*
X314675Y-194596D01*
Y-198819D02*
Y-194596D01*
X307493Y-187415D02*
Y-166087D01*
X309562Y-164018D01*
X261024Y-200394D02*
X266535Y-205906D01*
X289370D01*
X319685Y-245492D02*
Y-245276D01*
X318989Y-253024D02*
Y-246188D01*
X319685Y-245492D01*
X336614Y-286221D02*
Y-286004D01*
X337402Y-285217D02*
Y-260630D01*
X336614Y-286004D02*
X337402Y-285217D01*
X429134Y-246850D02*
X434646Y-241339D01*
X483831D01*
X470472Y-255906D02*
X473622Y-259055D01*
X470472Y-255906D02*
Y-246457D01*
X285816Y-203948D02*
X289370Y-200394D01*
X279932Y-203948D02*
X285816D01*
X275590Y-199606D02*
X279932Y-203948D01*
X292815Y-193376D02*
Y-187106D01*
X252428Y-300000D02*
X308268D01*
X246162Y-293733D02*
X252428Y-300000D01*
X315248Y-299430D02*
Y-299345D01*
X331157Y-299399D02*
X336811D01*
X328975Y-297216D02*
X331157Y-299399D01*
X317547Y-297216D02*
X328975D01*
X315333Y-299430D02*
X317547Y-297216D01*
X312904Y-297001D02*
Y-290837D01*
X315945Y-287795D01*
X312904Y-297001D02*
X315248Y-299345D01*
Y-299430D02*
X315333D01*
X307874Y-283465D02*
X313386D01*
X297556Y-293782D02*
X307874Y-283465D01*
X280414Y-293782D02*
X297556D01*
X316719Y-245276D02*
X319685D01*
X314862Y-243419D02*
X316719Y-245276D01*
X210630Y-144488D02*
X229134Y-162992D01*
Y-172835D02*
Y-162992D01*
X204331Y-197638D02*
X229134Y-172835D01*
X210630Y-130042D02*
X228346Y-112325D01*
X204331Y-232677D02*
Y-197638D01*
X228346Y-112325D02*
Y-107480D01*
X210630Y-144488D02*
Y-130042D01*
X223228Y-107480D02*
X225984Y-110236D01*
X202631Y-234305D02*
X203937Y-235611D01*
X209055Y-129778D02*
X225984Y-112849D01*
X202631Y-234305D02*
Y-197499D01*
X209055Y-144752D02*
Y-129778D01*
X203937Y-235827D02*
Y-235611D01*
X209055Y-144752D02*
X227834Y-163531D01*
Y-172296D02*
Y-163531D01*
X225984Y-112849D02*
Y-110236D01*
X202631Y-197499D02*
X227834Y-172296D01*
X234371Y-110905D02*
X238189Y-107087D01*
X207159Y-237371D02*
Y-236847D01*
X234371Y-119934D02*
X243426Y-128989D01*
X203966Y-240564D02*
X207159Y-237371D01*
X243426Y-146208D02*
Y-128989D01*
X203805Y-240564D02*
X203966D01*
X236733Y-152901D02*
X243426Y-146208D01*
X236733Y-207273D02*
Y-152901D01*
X234371Y-119934D02*
Y-110905D01*
X207159Y-236847D02*
X236733Y-207273D01*
X242126Y-145669D02*
Y-129527D01*
X235433Y-152362D02*
X242126Y-145669D01*
X235433Y-206735D02*
Y-152362D01*
X203979Y-238189D02*
X235433Y-206735D01*
X233071Y-120472D02*
Y-107087D01*
X203937Y-238189D02*
X203979D01*
X233071Y-120472D02*
X242126Y-129527D01*
X336811Y-299399D02*
X338306Y-300894D01*
X340836D01*
X345516Y-305574D01*
X346713D01*
X350492Y-301795D01*
Y-290807D01*
X347648Y-287963D02*
X350492Y-290807D01*
X338356Y-287963D02*
X347648D01*
X336614Y-286221D02*
X338356Y-287963D01*
X178339Y-136658D02*
X179877D01*
X178185Y-136811D02*
X178339Y-136658D01*
X179877D02*
X181335Y-135200D01*
Y-130082D01*
X163821Y-107480D02*
X169685D01*
X161853Y-109449D02*
X163821Y-107480D01*
X153543Y-109449D02*
X161853D01*
X150787Y-112205D02*
X153543Y-109449D01*
X150787Y-115748D02*
Y-112205D01*
X147638Y-118898D02*
X150787Y-115748D01*
X147638Y-127523D02*
Y-118898D01*
Y-127523D02*
X150627Y-130512D01*
X210236Y-44094D02*
Y-40431D01*
X215354Y-42126D02*
Y-38291D01*
X220866Y-39764D02*
Y-35972D01*
X100394Y-30315D02*
X109153D01*
X536434Y-256004D02*
X540945D01*
X535257Y-250886D02*
X538976D01*
X533249Y-245374D02*
X536614D01*
X611553Y-247377D02*
Y-238583D01*
X612143Y-231711D02*
X612751Y-231102D01*
X611553Y-232436D02*
X612143Y-231846D01*
X612751Y-231102D02*
X612887D01*
X612143Y-231846D02*
Y-231711D01*
X611553Y-238583D02*
Y-232436D01*
X613022Y-231102D02*
X613630Y-230494D01*
Y-229283D02*
X616929Y-225984D01*
X612887Y-231102D02*
X613022D01*
X613630Y-230494D02*
Y-229283D01*
X591339Y-189370D02*
Y-186417D01*
X590748Y-185827D02*
X591339Y-186417D01*
X581890Y-180512D02*
Y-174016D01*
Y-180512D02*
X587205Y-185827D01*
X589278Y-175105D02*
X589764Y-175591D01*
X588091Y-174016D02*
X589180Y-175105D01*
X589764Y-175689D02*
Y-175591D01*
X589180Y-175105D02*
X589278D01*
X581890Y-174016D02*
X588091D01*
X589245Y-162282D02*
X589730Y-161796D01*
X589146Y-162282D02*
X589245D01*
X589730Y-161796D02*
Y-161698D01*
X587530Y-163898D02*
X589146Y-162282D01*
X582165Y-163898D02*
X587530D01*
X581299Y-229134D02*
Y-223467D01*
X591461Y-213305D01*
X577559Y-224016D02*
X585335Y-216240D01*
Y-214173D01*
X577559Y-242520D02*
Y-224016D01*
X585335Y-214173D02*
X587972D01*
X577559Y-242520D02*
X578642Y-243602D01*
X581890D01*
X588922Y-206639D02*
X591461Y-209177D01*
X588922Y-206639D02*
Y-206462D01*
X591461Y-213305D02*
Y-209177D01*
X581299Y-229134D02*
X584646Y-232480D01*
X589370Y-201575D02*
X593376Y-205581D01*
Y-214104D02*
Y-205581D01*
X587008Y-220472D02*
X593376Y-214104D01*
X587008Y-224705D02*
Y-220472D01*
Y-224705D02*
X590158Y-227854D01*
X587972Y-214173D02*
X589154Y-212992D01*
X589370D01*
X585450Y-206577D02*
X588807D01*
X585335Y-206693D02*
X585450Y-206577D01*
X586909Y-199114D02*
X589370Y-201575D01*
X586909Y-199114D02*
Y-196850D01*
X10630Y-292126D02*
X18110D01*
X26870Y-298727D02*
Y-294882D01*
X425938Y-200000D02*
X426233Y-199705D01*
X432237D01*
X424409Y-205512D02*
Y-201529D01*
X425938Y-200000D01*
X189764Y-100787D02*
Y-95927D01*
X150153Y771D02*
X151751Y2369D01*
X150000Y-787D02*
X150153Y-634D01*
X151751Y2369D02*
Y2505D01*
X150153Y-634D02*
Y771D01*
X477872Y-304428D02*
X478346Y-304902D01*
X477872Y-304428D02*
Y-301826D01*
X478346Y-305118D02*
Y-304902D01*
X474409Y-265748D02*
X478876D01*
X618110Y-64961D02*
Y-62205D01*
X613779Y-64961D02*
X618110D01*
Y-62205D02*
Y-59842D01*
X612756D02*
X618110D01*
X233238Y-139203D02*
Y-131919D01*
X233268Y-131890D01*
X233209Y-139232D02*
X233238Y-139203D01*
X228179Y-138691D02*
Y-132707D01*
X228150Y-132677D02*
X228179Y-132707D01*
Y-138691D02*
X228209Y-138721D01*
X199193Y-110650D02*
Y-105925D01*
X198031Y-111811D02*
X199193Y-110650D01*
X204193Y-138257D02*
Y-130866D01*
X199193Y-138680D02*
Y-130787D01*
X175823Y-134449D02*
X178185Y-136811D01*
X170311Y-134449D02*
X175823D01*
X164012Y-128150D02*
X170311Y-134449D01*
X177398Y-132874D02*
X178185Y-133661D01*
X173320Y-132874D02*
X177398D01*
X165839Y-125394D02*
X173320Y-132874D01*
X163724Y-125394D02*
X165839D01*
X160469Y-128937D02*
X162086Y-127320D01*
Y-127031D01*
X163724Y-125394D01*
X150627Y-130512D02*
X152201Y-128937D01*
X157319D01*
X158894Y-136417D02*
X162437D01*
X158107Y-137205D02*
X158894Y-136417D01*
X162339Y-139906D02*
Y-136516D01*
X162437Y-136417D01*
X162241Y-140004D02*
X162339Y-139906D01*
X59016Y-58729D02*
Y-57706D01*
X64528Y-64085D02*
Y-58729D01*
Y-64085D02*
X66102D01*
X388713Y-141339D02*
Y-135039D01*
X387689Y-141339D02*
X388713D01*
X366043Y-153937D02*
X373083D01*
X373228Y-162598D02*
Y-157087D01*
X373083D02*
X373228D01*
X378346Y-161811D02*
Y-157087D01*
X378083D02*
X378346D01*
X388713Y-135039D02*
Y-128731D01*
X408268Y-124409D02*
X413911D01*
X427658Y-132677D02*
X427900D01*
X422835Y-137992D02*
Y-131791D01*
Y-137992D02*
X423917D01*
X400984Y-129921D02*
Y-127102D01*
X403937Y-129528D02*
X408268D01*
X403937Y-129921D02*
Y-129528D01*
X412205Y-129609D02*
X415748D01*
X412205D02*
Y-129528D01*
X418898Y-129753D02*
Y-124409D01*
X417585D02*
X418898D01*
X422047Y-105512D02*
Y-101969D01*
X418898Y-104643D02*
Y-100000D01*
X418071Y-104643D02*
X418898D01*
X31398Y16339D02*
X31477Y16418D01*
X281890Y-200771D02*
Y-196715D01*
Y-193836D02*
Y-188583D01*
X333465Y-292913D02*
X337931D01*
X340809D02*
X345161D01*
X314961Y-293701D02*
X319033D01*
X321912D02*
X325776D01*
X317009Y-239764D02*
X324151D01*
X327030D02*
X333714D01*
X18110Y-292815D02*
Y-292126D01*
X26870Y-298727D02*
X27067D01*
X8661Y-189665D02*
Y-185755D01*
X9843D01*
X13780Y-193012D02*
Y-190551D01*
X8661Y-193012D02*
X13780D01*
X190354Y-401230D02*
Y-377411D01*
Y-401230D02*
X190551Y-401427D01*
X158736Y-377411D02*
X178543D01*
X151260Y-402150D02*
X151753Y-401657D01*
Y-384394D02*
X158736Y-377411D01*
X151753Y-401657D02*
Y-384394D01*
X241811Y-404100D02*
X241941Y-403970D01*
X206378Y-404100D02*
X206441Y-404037D01*
X273307Y-404100D02*
X273441Y-403966D01*
D42*
X109055Y-30315D02*
D03*
X112205D02*
D03*
X160863Y-121457D02*
D03*
X157713D02*
D03*
X425197Y-105512D02*
D03*
X422047D02*
D03*
X92732Y-13129D02*
D03*
X89583D02*
D03*
X43268Y-48355D02*
D03*
X46417D02*
D03*
X43268Y-43355D02*
D03*
X46417D02*
D03*
X158107Y-137205D02*
D03*
X154957D02*
D03*
X162437Y-136417D02*
D03*
X165587D02*
D03*
X43701Y-148819D02*
D03*
X46850D02*
D03*
X161596Y-117597D02*
D03*
X164746D02*
D03*
X156434Y-132185D02*
D03*
X159583D02*
D03*
X160863Y-125000D02*
D03*
X157713D02*
D03*
X160469Y-128937D02*
D03*
X157319D02*
D03*
D43*
X425938Y-194488D02*
D03*
Y-200000D02*
D03*
X162992Y-42913D02*
D03*
Y-48425D02*
D03*
D46*
X555512Y-340158D02*
D03*
X561024D02*
D03*
X535827Y-338976D02*
D03*
X530315D02*
D03*
X568898Y-319291D02*
D03*
X563386D02*
D03*
X536221Y-300787D02*
D03*
X530709D02*
D03*
X128159Y-65403D02*
D03*
X122648D02*
D03*
X117825Y-47401D02*
D03*
X123337D02*
D03*
X149606Y-80315D02*
D03*
X144095D02*
D03*
X222835Y-138189D02*
D03*
X217323D02*
D03*
X198031Y-111811D02*
D03*
X192520D02*
D03*
D52*
X587625Y-281567D02*
D03*
Y-279992D02*
D03*
Y-278418D02*
D03*
X591680D02*
D03*
Y-279992D02*
D03*
Y-281567D02*
D03*
D53*
X589652Y-279992D02*
D03*
D60*
X43925Y-154365D02*
D03*
X46878D02*
D03*
X585335Y-214173D02*
D03*
X582382D02*
D03*
X586909Y-196850D02*
D03*
X583957D02*
D03*
X582382Y-206693D02*
D03*
X585335D02*
D03*
D64*
X590748Y-185827D02*
D03*
X587205D02*
D03*
D68*
X589764Y-178642D02*
D03*
Y-175689D02*
D03*
X589730Y-158745D02*
D03*
Y-161698D02*
D03*
D69*
X581890Y-243602D02*
D03*
Y-240059D02*
D03*
X590158Y-224311D02*
D03*
Y-227854D02*
D03*
X584646Y-228937D02*
D03*
Y-232480D02*
D03*
D86*
X97553Y-77165D02*
D03*
X93785D02*
D03*
D87*
X544471Y-273290D02*
D03*
Y-270412D02*
D03*
X580866Y-278931D02*
D03*
Y-276053D02*
D03*
X596220Y-279718D02*
D03*
Y-276840D02*
D03*
X477872Y-298948D02*
D03*
Y-301826D02*
D03*
X189764Y-95927D02*
D03*
Y-93049D02*
D03*
X151751Y2505D02*
D03*
Y5383D02*
D03*
X209449Y4195D02*
D03*
Y1317D02*
D03*
X203839Y-1514D02*
D03*
Y-4392D02*
D03*
X214173Y-1711D02*
D03*
Y-4589D02*
D03*
X204537Y-76439D02*
D03*
Y-73561D02*
D03*
X214173Y-76242D02*
D03*
Y-73364D02*
D03*
X108661Y-47638D02*
D03*
Y-44760D02*
D03*
X281890Y-196715D02*
D03*
Y-193836D02*
D03*
X158661Y-101429D02*
D03*
Y-98551D02*
D03*
D88*
X413911Y-124409D02*
D03*
X417585D02*
D03*
X114829Y-16142D02*
D03*
X111155D02*
D03*
D89*
X64528Y-58729D02*
D03*
Y-53218D02*
D03*
X101969Y-49213D02*
D03*
Y-43701D02*
D03*
X164961Y-98819D02*
D03*
Y-104331D02*
D03*
D106*
X442028Y-154331D02*
D03*
X445374D02*
D03*
X71752Y787D02*
D03*
X68405D02*
D03*
X53248Y-5709D02*
D03*
X56595D02*
D03*
X536434Y-256004D02*
D03*
X533088D02*
D03*
X535257Y-250886D02*
D03*
X531910D02*
D03*
X533249Y-245374D02*
D03*
X529902D02*
D03*
X414725Y-104643D02*
D03*
X418071D02*
D03*
X52854Y394D02*
D03*
X49508D02*
D03*
X64862Y-5709D02*
D03*
X61516D02*
D03*
X92831Y-16929D02*
D03*
X89484D02*
D03*
X23524Y-294882D02*
D03*
X26870D02*
D03*
D113*
X96063Y-48687D02*
D03*
Y-45013D02*
D03*
X153150Y-99738D02*
D03*
Y-103412D02*
D03*
D119*
X437303Y-144390D02*
D03*
Y-147736D02*
D03*
X441732Y-144390D02*
D03*
Y-147736D02*
D03*
X452854Y-144390D02*
D03*
Y-147736D02*
D03*
X210236Y-40431D02*
D03*
Y-37085D02*
D03*
X215354Y-38291D02*
D03*
Y-34944D02*
D03*
X220866Y-35972D02*
D03*
Y-32626D02*
D03*
X18110Y-296161D02*
D03*
Y-292815D02*
D03*
X8661Y-193012D02*
D03*
Y-189665D02*
D03*
D120*
X558375Y-280755D02*
D03*
X555497D02*
D03*
X478876Y-265748D02*
D03*
X481754D02*
D03*
X495805Y-252362D02*
D03*
X498683D02*
D03*
X509116Y-260136D02*
D03*
X506238D02*
D03*
X496199Y-259842D02*
D03*
X499077D02*
D03*
X564506Y-261119D02*
D03*
X567384D02*
D03*
X574766Y-261122D02*
D03*
X571888D02*
D03*
X340809Y-292913D02*
D03*
X337931D02*
D03*
X321912Y-293701D02*
D03*
X319033D02*
D03*
X327030Y-239764D02*
D03*
X324151D02*
D03*
X376514Y-232972D02*
D03*
X379392D02*
D03*
X611553Y-238583D02*
D03*
X614431D02*
D03*
X612887Y-231102D02*
D03*
X615765D02*
D03*
D124*
X596220Y-283876D02*
D03*
Y-287644D02*
D03*
X580866Y-283482D02*
D03*
Y-287250D02*
D03*
D141*
X281102Y-401427D02*
D03*
X159055D02*
D03*
X155118D02*
D03*
X186614D02*
D03*
X182677D02*
D03*
X241732D02*
D03*
X273228D02*
D03*
X269291D02*
D03*
X257480D02*
D03*
X237795D02*
D03*
X253543D02*
D03*
X222047D02*
D03*
X218110D02*
D03*
X210236D02*
D03*
X206299D02*
D03*
X190551D02*
D03*
X166929D02*
D03*
X170866D02*
D03*
X174803D02*
D03*
X178740D02*
D03*
X229921D02*
D03*
X214173D02*
D03*
X202362D02*
D03*
X249606D02*
D03*
X265354D02*
D03*
X245669D02*
D03*
X277165D02*
D03*
X261417D02*
D03*
X233858D02*
D03*
X225984D02*
D03*
X162992D02*
D03*
D142*
X151181Y-399477D02*
D03*
D210*
X603110Y-805D02*
D03*
D211*
X574409Y7445D02*
D03*
D212*
Y-9055D02*
D03*
X552709Y7445D02*
D03*
Y-9055D02*
D03*
D217*
X321260Y-145669D02*
D03*
Y-135669D02*
D03*
Y-125669D02*
D03*
X194882Y394D02*
D03*
X496457Y-271358D02*
D03*
D218*
X194882Y-78347D02*
D03*
X575197Y-271358D02*
D03*
D231*
X529282Y-312272D02*
Y-300787D01*
X562205Y-309842D02*
Y-309350D01*
Y-319291D02*
Y-309842D01*
X555512Y-334623D02*
Y-330315D01*
X537156Y-338976D02*
Y-328837D01*
X536221Y-312272D02*
Y-300787D01*
X108661Y-59842D02*
Y-48213D01*
X129341Y-74575D02*
Y-65403D01*
X144095Y-80315D02*
Y-71072D01*
X97553Y-79921D02*
X105512D01*
X129341Y-75067D02*
Y-74575D01*
X157087Y-42913D02*
X162992D01*
X152756Y-49606D02*
X153937Y-48425D01*
X162992D01*
X148632Y-49655D02*
X148681Y-49606D01*
X152756D01*
X157480Y-73228D02*
Y-72830D01*
X151970Y-71072D02*
X155723D01*
X157480Y-72830D01*
X568405Y-303150D02*
X569685D01*
X562205Y-309350D02*
X568405Y-303150D01*
X105282Y-19291D02*
Y-16142D01*
X111155D01*
X121467Y-74575D02*
Y-65403D01*
X117323Y-74410D02*
X121301D01*
X121467Y-74575D01*
X112324Y-69411D02*
X117323Y-74410D01*
X92212Y-69411D02*
X112324D01*
X86614Y-63814D02*
X92212Y-69411D01*
X86614Y-63814D02*
Y-56299D01*
X119685Y-42126D02*
X123694D01*
X118504Y-40945D02*
X119685Y-42126D01*
X107874Y-59842D02*
X108661D01*
X101969D02*
Y-49213D01*
X99606Y-59842D02*
X101969D01*
X96063D02*
X99606D01*
X96063D02*
Y-48687D01*
X97553Y-79921D02*
Y-77165D01*
X85039D02*
X93785D01*
X85039Y-77559D02*
Y-77165D01*
X129341Y-75067D02*
X133408Y-79134D01*
X135433D01*
X157038Y-41781D02*
X157087Y-41732D01*
X148632Y-41781D02*
X157038D01*
X123337Y-47401D02*
Y-42483D01*
X123694Y-42126D01*
X125516Y-40304D01*
Y-36689D01*
X125984Y-36220D01*
X157087Y-42913D02*
Y-41732D01*
X144095Y-71072D02*
X144096D01*
X144095Y-80315D02*
X144095D01*
X128159Y-65403D02*
X129341D01*
X121467D02*
X122648D01*
X535827Y-338976D02*
X537156D01*
X535827Y-345276D02*
X535827D01*
Y-338976D01*
X561024Y-340158D02*
Y-330315D01*
X555556Y-340113D02*
Y-334667D01*
X555512Y-340158D02*
X555556Y-340113D01*
X555512Y-334623D02*
X555556Y-334667D01*
X553150Y-330315D02*
X555512D01*
X568898Y-319291D02*
Y-319009D01*
X570079Y-309921D02*
Y-309842D01*
X562205Y-319291D02*
X563386D01*
X536221Y-312272D02*
X537156D01*
X529282Y-300787D02*
X530709D01*
X529282Y-338976D02*
Y-328837D01*
Y-338976D02*
X530315D01*
D236*
X298031Y-115512D02*
D03*
Y-145512D02*
D03*
Y-125512D02*
D03*
Y-135512D02*
D03*
D237*
Y-155512D02*
D03*
D238*
X321260Y-155669D02*
D03*
D239*
X0Y0D02*
D03*
X0Y-378395D02*
D03*
D240*
X608268Y-288779D02*
D03*
Y-271260D02*
D03*
D241*
X620079Y-263583D02*
D03*
Y-296457D02*
D03*
D242*
X354035Y-38976D02*
D03*
X424803D02*
D03*
X535827Y-112205D02*
D03*
D243*
X390462Y-181769D02*
D03*
X311722D02*
D03*
X390452Y-329890D02*
D03*
X311712D02*
D03*
X261082Y-294702D02*
D03*
Y-215962D02*
D03*
X448573Y-215972D02*
D03*
Y-294712D02*
D03*
D244*
X186221Y-334252D02*
D03*
X198031D02*
D03*
X58268Y-163779D02*
D03*
X209842Y-334252D02*
D03*
X58268Y-323622D02*
D03*
X218110Y-163779D02*
D03*
X58268Y-243701D02*
D03*
X174221Y-334252D02*
D03*
X218110Y-323622D02*
D03*
X162221Y-334252D02*
D03*
X174221D02*
D03*
X198031D02*
D03*
X209842D02*
D03*
X218110Y-163779D02*
D03*
Y-323622D02*
D03*
X58268D02*
D03*
Y-243701D02*
D03*
Y-163779D02*
D03*
X186221Y-334252D02*
D03*
X162221D02*
D03*
D245*
X200876Y-315719D02*
D03*
X75768Y-321622D02*
D03*
X78268Y-159780D02*
D03*
X200610Y-171879D02*
D03*
D246*
X-18464Y-326781D02*
D03*
X1535D02*
D03*
Y-306781D02*
D03*
X-18464D02*
D03*
X-18465Y-273630D02*
D03*
X1535D02*
D03*
Y-253630D02*
D03*
X-18465D02*
D03*
Y-220480D02*
D03*
X1535D02*
D03*
Y-200480D02*
D03*
X-18465D02*
D03*
X-18464Y-167332D02*
D03*
X1535D02*
D03*
Y-147332D02*
D03*
X-18464D02*
D03*
D247*
X-8465Y-316781D02*
D03*
X-8465Y-263630D02*
D03*
Y-210480D02*
D03*
X-8465Y-157332D02*
D03*
D248*
X609449Y-98189D02*
D03*
D249*
Y-108189D02*
D03*
Y-118189D02*
D03*
Y-128189D02*
D03*
Y-138189D02*
D03*
Y-148189D02*
D03*
X619449Y-98189D02*
D03*
Y-108189D02*
D03*
Y-118189D02*
D03*
Y-128189D02*
D03*
Y-138189D02*
D03*
Y-148189D02*
D03*
D250*
X181534Y-387757D02*
D03*
X522047Y-270866D02*
D03*
X496620Y-310492D02*
D03*
X61811Y787D02*
D03*
X593307Y-292126D02*
D03*
X245325Y-120837D02*
D03*
X500049Y-256633D02*
D03*
X585039Y-266142D02*
D03*
X560630Y-269291D02*
D03*
X599044Y-275032D02*
D03*
X585039Y-272835D02*
D03*
X581496D02*
D03*
X548425Y-269632D02*
D03*
X541093Y-284626D02*
D03*
X541411Y-269932D02*
D03*
X536489Y-269182D02*
D03*
X554724Y-272441D02*
D03*
X555460Y-284401D02*
D03*
X574406Y-280807D02*
D03*
X567525Y-286203D02*
D03*
X581890Y-290158D02*
D03*
X583815Y-275386D02*
D03*
X614822Y-250158D02*
D03*
X604724Y-274803D02*
D03*
X321260Y-166142D02*
D03*
X323622Y-166535D02*
D03*
X150394Y-140157D02*
D03*
X317323Y-114961D02*
D03*
X321260D02*
D03*
X320761Y-183851D02*
D03*
X309449Y-211811D02*
D03*
X313386Y-212598D02*
D03*
X124016Y-110236D02*
D03*
X222351Y-98694D02*
D03*
X245276Y-115748D02*
D03*
X211648Y-103695D02*
D03*
X44001Y-137747D02*
D03*
X100729Y-127872D02*
D03*
X-23622Y-181102D02*
D03*
X98761Y-129872D02*
D03*
X57422Y-128927D02*
D03*
X89312Y-128140D02*
D03*
X84981D02*
D03*
X80651D02*
D03*
X89312Y-123809D02*
D03*
X84981D02*
D03*
X80651D02*
D03*
X89312Y-119478D02*
D03*
X84981D02*
D03*
X80651D02*
D03*
X98761Y-125872D02*
D03*
X58407Y-137589D02*
D03*
X85044Y-139557D02*
D03*
X81044D02*
D03*
X89044D02*
D03*
X71202Y-138095D02*
D03*
X79044Y-137936D02*
D03*
X83044D02*
D03*
X91044D02*
D03*
X87044D02*
D03*
X68889Y-137453D02*
D03*
X98761Y-117746D02*
D03*
Y-121871D02*
D03*
X52501Y-119872D02*
D03*
X44134Y-115080D02*
D03*
X44621Y-110628D02*
D03*
X58210Y-108061D02*
D03*
X91044Y-110061D02*
D03*
X78918Y-110029D02*
D03*
X82918D02*
D03*
X86981D02*
D03*
X80981Y-108061D02*
D03*
X88981D02*
D03*
X84981D02*
D03*
X139370Y-118898D02*
D03*
X262724Y-107813D02*
D03*
X253082Y-110236D02*
D03*
X317828Y-161260D02*
D03*
X313878Y-161597D02*
D03*
X286221Y-124803D02*
D03*
X285827Y-137795D02*
D03*
X285384Y-154492D02*
D03*
X284646Y-128347D02*
D03*
X284252Y-144095D02*
D03*
X282058Y-151217D02*
D03*
X281890Y-155905D02*
D03*
X281496Y-124409D02*
D03*
X280709Y-137795D02*
D03*
X276650Y-128810D02*
D03*
X276083Y-152559D02*
D03*
Y-141142D02*
D03*
X255906Y-126378D02*
D03*
Y-131496D02*
D03*
Y-137008D02*
D03*
Y-142126D02*
D03*
X257480Y-150394D02*
D03*
X255512Y-146850D02*
D03*
X140551Y-116535D02*
D03*
X368110Y-330315D02*
D03*
X262006Y-387255D02*
D03*
X365354Y-330315D02*
D03*
X265158Y-387253D02*
D03*
X374114Y-346144D02*
D03*
X246339Y-386975D02*
D03*
X249410Y-387253D02*
D03*
X371359Y-346144D02*
D03*
X237992Y-374655D02*
D03*
X367422Y-346144D02*
D03*
X241929Y-374655D02*
D03*
X364666Y-346144D02*
D03*
X354036D02*
D03*
X206496Y-374655D02*
D03*
X351280Y-346144D02*
D03*
X210433Y-374655D02*
D03*
X360729Y-346144D02*
D03*
X229331Y-387253D02*
D03*
X357973Y-346144D02*
D03*
X232480Y-387253D02*
D03*
X212795D02*
D03*
X215945D02*
D03*
X356299Y-330315D02*
D03*
X353543D02*
D03*
X218445Y-374108D02*
D03*
X222638Y-374655D02*
D03*
X364567Y-326378D02*
D03*
X357575Y-327776D02*
D03*
X357480Y-332677D02*
D03*
X350787Y-329921D02*
D03*
X359652Y-326841D02*
D03*
X362408D02*
D03*
X205906Y-372441D02*
D03*
X211024D02*
D03*
X222835Y-372047D02*
D03*
X217323Y-371654D02*
D03*
X237795D02*
D03*
X242897Y-371864D02*
D03*
X250394Y-375984D02*
D03*
X259449Y-373228D02*
D03*
X268504Y-372047D02*
D03*
X274803Y-372441D02*
D03*
X266929Y-385039D02*
D03*
X243701Y-389370D02*
D03*
X250394Y-384646D02*
D03*
X227953Y-383858D02*
D03*
X233858Y-384646D02*
D03*
X213386D02*
D03*
X513386Y-199213D02*
D03*
X521654Y-198819D02*
D03*
X591339Y-189764D02*
D03*
X153225Y-121747D02*
D03*
X133099Y-136519D02*
D03*
X24500Y-8429D02*
D03*
X603150Y-235946D02*
D03*
X604316Y-246600D02*
D03*
X152756Y-65354D02*
D03*
Y-57480D02*
D03*
Y-49606D02*
D03*
X157480Y-73228D02*
D03*
X284646Y-291732D02*
D03*
X381890Y-183858D02*
D03*
X384646Y-184252D02*
D03*
X359842Y-161024D02*
D03*
X363386Y-160630D02*
D03*
X367717D02*
D03*
X454775Y-308565D02*
D03*
X569685Y-303150D02*
D03*
X608268Y-84252D02*
D03*
X383083Y-161839D02*
D03*
X421313Y-174784D02*
D03*
X396850Y-249016D02*
D03*
X129063Y-136618D02*
D03*
X38613Y-53355D02*
D03*
X172674Y-138386D02*
D03*
X613406Y-89494D02*
D03*
X388189Y-162205D02*
D03*
X419798Y-176745D02*
D03*
X401575Y-249213D02*
D03*
X126307Y-136224D02*
D03*
X38583Y-58355D02*
D03*
X170311Y-139961D02*
D03*
X491732Y-149213D02*
D03*
X500394Y-145669D02*
D03*
X496063Y-145276D02*
D03*
X491732D02*
D03*
X550391Y-243310D02*
D03*
X477165Y-247244D02*
D03*
X539370Y-228740D02*
D03*
X542913D02*
D03*
X561024Y-183465D02*
D03*
Y-186614D02*
D03*
X-4724Y-283071D02*
D03*
X35433Y-129528D02*
D03*
X32283D02*
D03*
X28740D02*
D03*
X35433Y-50787D02*
D03*
X149935Y-124206D02*
D03*
X150233Y-119882D02*
D03*
X429528Y-231496D02*
D03*
X364173Y-280315D02*
D03*
X462205Y-255118D02*
D03*
X464961Y-125197D02*
D03*
X50000Y-44094D02*
D03*
X324016Y-42913D02*
D03*
X318898Y-43307D02*
D03*
X324016Y-39764D02*
D03*
X318898D02*
D03*
X324016Y-35827D02*
D03*
X318898D02*
D03*
X505118Y-24016D02*
D03*
X500787Y-24409D02*
D03*
X496457Y-24016D02*
D03*
X505118Y-20079D02*
D03*
X500787D02*
D03*
X496457D02*
D03*
X245669Y-74016D02*
D03*
X246063Y-70079D02*
D03*
X241732Y-74016D02*
D03*
Y-70079D02*
D03*
X326772Y-73622D02*
D03*
X322441D02*
D03*
X317717Y-73228D02*
D03*
X326772Y-69291D02*
D03*
X322441D02*
D03*
X317717D02*
D03*
X427953Y-206299D02*
D03*
X481496Y-197244D02*
D03*
X468504Y-44488D02*
D03*
X463779D02*
D03*
X458661Y-44094D02*
D03*
X468898Y-39764D02*
D03*
X463779Y-39370D02*
D03*
X458661D02*
D03*
X295669Y-45276D02*
D03*
X290945D02*
D03*
X295276Y-40945D02*
D03*
X290945D02*
D03*
X295276Y-35433D02*
D03*
X290945D02*
D03*
X118504Y-40945D02*
D03*
X85039Y-77559D02*
D03*
X383465Y-234252D02*
D03*
X389764D02*
D03*
X386614Y-237402D02*
D03*
Y-231102D02*
D03*
X611811Y-221260D02*
D03*
X426772Y-179528D02*
D03*
X418898Y-245276D02*
D03*
X602105Y-99109D02*
D03*
X597244Y-108661D02*
D03*
X592913Y-116535D02*
D03*
X594488Y-132677D02*
D03*
X43701Y-34646D02*
D03*
X51287Y-126878D02*
D03*
X13386D02*
D03*
X29543Y-345214D02*
D03*
X240158Y-278740D02*
D03*
X26378Y-20472D02*
D03*
X24409Y-16535D02*
D03*
X26378Y-10630D02*
D03*
X35433Y15354D02*
D03*
X36220Y8268D02*
D03*
X35827Y1575D02*
D03*
X19685Y-2362D02*
D03*
X20079Y3937D02*
D03*
Y10630D02*
D03*
Y17323D02*
D03*
X298819Y-269685D02*
D03*
X391339Y-277953D02*
D03*
X299606Y-185433D02*
D03*
X231102Y-239764D02*
D03*
X230709Y-242913D02*
D03*
X399213Y-193307D02*
D03*
X204331Y-101575D02*
D03*
X432283Y-254724D02*
D03*
X496063Y-244094D02*
D03*
X173228Y-117323D02*
D03*
X261024Y-200394D02*
D03*
X381890Y-254331D02*
D03*
X318989Y-253024D02*
D03*
X337402Y-260630D02*
D03*
X429134Y-246850D02*
D03*
X483831Y-241339D02*
D03*
X488189Y-216535D02*
D03*
X500971Y-219896D02*
D03*
X470472Y-246457D02*
D03*
X476968Y-76378D02*
D03*
X462992D02*
D03*
X289370Y-205906D02*
D03*
X343701Y-200394D02*
D03*
X357480Y-214567D02*
D03*
X153150Y-113386D02*
D03*
X226378Y-32677D02*
D03*
X100394Y-30315D02*
D03*
X383071Y-276772D02*
D03*
X402756Y-281102D02*
D03*
X616929Y-225984D02*
D03*
X611614Y-186107D02*
D03*
X586221Y-178740D02*
D03*
X591339Y-144488D02*
D03*
X586614Y-158661D02*
D03*
X582165Y-163898D02*
D03*
X581890Y-174016D02*
D03*
X579134Y-214006D02*
D03*
X581890Y-235925D02*
D03*
X584646Y-225197D02*
D03*
X590188Y-221161D02*
D03*
X608661Y-220472D02*
D03*
X589370Y-212992D02*
D03*
X588922Y-206462D02*
D03*
X583858Y-192913D02*
D03*
X589370Y-201575D02*
D03*
X329528Y-181890D02*
D03*
X307087Y-198819D02*
D03*
X279134Y-230315D02*
D03*
X280315Y-226378D02*
D03*
X277165Y-236221D02*
D03*
X281496Y-237402D02*
D03*
X27559Y-337402D02*
D03*
X288583Y-237402D02*
D03*
X293307Y-237008D02*
D03*
X341339Y-277953D02*
D03*
X407874Y-216535D02*
D03*
X408760Y-238189D02*
D03*
X462473Y-277635D02*
D03*
X321850Y-283465D02*
D03*
X461417Y-305118D02*
D03*
X343701Y-209449D02*
D03*
X347638Y-202756D02*
D03*
X383071Y-168110D02*
D03*
X598397Y-88288D02*
D03*
X603543Y-87795D02*
D03*
X135433Y-79134D02*
D03*
X424409Y-205512D02*
D03*
X428346Y-187795D02*
D03*
X140070Y-132385D02*
D03*
X140116Y-124048D02*
D03*
X141339Y394D02*
D03*
X180610Y-87795D02*
D03*
X198524D02*
D03*
X197244Y-102756D02*
D03*
X181004Y-101181D02*
D03*
X177559Y-87795D02*
D03*
X197638Y-97638D02*
D03*
X182283Y-97244D02*
D03*
X182677Y-94488D02*
D03*
X189764Y-88189D02*
D03*
Y-100787D02*
D03*
X196850Y-94488D02*
D03*
X161417Y-25984D02*
D03*
X169291Y13386D02*
D03*
Y9646D02*
D03*
X159843D02*
D03*
X151181Y14173D02*
D03*
X142520Y13189D02*
D03*
X144685Y-11811D02*
D03*
X162598Y-9449D02*
D03*
X153543Y-10433D02*
D03*
X162598Y-13189D02*
D03*
Y-1575D02*
D03*
X151181Y18110D02*
D03*
X137598Y-6299D02*
D03*
X134055D02*
D03*
X149803Y-9238D02*
D03*
X150000Y-787D02*
D03*
X151782Y10443D02*
D03*
X473303Y-276476D02*
D03*
X479331Y-294626D02*
D03*
X487402Y-256988D02*
D03*
X485827Y-279429D02*
D03*
X476772Y-254035D02*
D03*
X473622Y-259055D02*
D03*
X476378Y-273622D02*
D03*
X486221Y-265748D02*
D03*
X474409D02*
D03*
X480315Y-259744D02*
D03*
Y-271752D02*
D03*
X548819Y-300787D02*
D03*
X489567Y-310236D02*
D03*
X492323Y-303543D02*
D03*
X495866D02*
D03*
X483465Y-291535D02*
D03*
X476772Y-291929D02*
D03*
X466142Y-294685D02*
D03*
Y-298228D02*
D03*
X461417Y-312099D02*
D03*
X473819Y-315354D02*
D03*
X484842Y-317717D02*
D03*
X493110Y-310236D02*
D03*
X461024Y-302756D02*
D03*
X498425Y-307087D02*
D03*
X478346Y-305118D02*
D03*
X477362Y-313767D02*
D03*
X596865Y-266396D02*
D03*
X594765D02*
D03*
X624938Y-196373D02*
D03*
X624926Y-201353D02*
D03*
X624938Y-206373D02*
D03*
X624918Y-211353D02*
D03*
X625079Y-173898D02*
D03*
X624685Y-163898D02*
D03*
X551968Y-297638D02*
D03*
X127165Y-12598D02*
D03*
X118110Y-36220D02*
D03*
X117717Y-47293D02*
D03*
X121653Y-52756D02*
D03*
Y-31496D02*
D03*
X404493Y-224149D02*
D03*
X404626Y-219685D02*
D03*
X578332Y-261235D02*
D03*
X507874Y-255906D02*
D03*
X534814Y-297190D02*
D03*
X528960Y-296841D02*
D03*
X495276Y-298130D02*
D03*
X503346Y-297967D02*
D03*
X507480Y-298130D02*
D03*
X501181D02*
D03*
X516929D02*
D03*
X522835Y-297736D02*
D03*
X540945Y-297342D02*
D03*
X546457D02*
D03*
X562205Y-297736D02*
D03*
X568110D02*
D03*
X570472D02*
D03*
X576378D02*
D03*
X571260Y-256791D02*
D03*
X568898D02*
D03*
X550000Y-255610D02*
D03*
X540945Y-256004D02*
D03*
X538976Y-250886D02*
D03*
X536614Y-245374D02*
D03*
X518110Y-255217D02*
D03*
X522047Y-249705D02*
D03*
X524016Y-243799D02*
D03*
X502362Y-257185D02*
D03*
X504331D02*
D03*
X513386Y-254429D02*
D03*
X508268Y-251673D02*
D03*
X564173Y-255906D02*
D03*
X494882Y-262303D02*
D03*
X495669Y-255512D02*
D03*
X209449Y7087D02*
D03*
X203937Y1969D02*
D03*
X214173Y1181D02*
D03*
Y-79134D02*
D03*
X205118Y-79380D02*
D03*
X214567Y-11417D02*
D03*
X211811Y-16535D02*
D03*
X209055Y-7480D02*
D03*
Y-5512D02*
D03*
X209449Y-3543D02*
D03*
X216535Y-25197D02*
D03*
X211024Y-21260D02*
D03*
X220866Y-39764D02*
D03*
X215354Y-42126D02*
D03*
X210236Y-44094D02*
D03*
X210630Y-53150D02*
D03*
X209541Y-58689D02*
D03*
X209449Y-72047D02*
D03*
Y-74410D02*
D03*
X168504Y-79528D02*
D03*
Y-73622D02*
D03*
Y-71260D02*
D03*
Y-65354D02*
D03*
X168898Y-49606D02*
D03*
Y-44094D02*
D03*
X168504Y-37795D02*
D03*
Y-31890D02*
D03*
Y-25984D02*
D03*
X168110Y-20079D02*
D03*
Y-4331D02*
D03*
Y-10630D02*
D03*
X168273Y-6496D02*
D03*
X168110Y1575D02*
D03*
X101181Y-38583D02*
D03*
X144095Y-80315D02*
D03*
X149606D02*
D03*
X117323Y-65354D02*
D03*
X121467Y-74575D02*
D03*
X-18601Y-349409D02*
D03*
X87795Y-99606D02*
D03*
X540551Y-340945D02*
D03*
X535827Y-345276D02*
D03*
X555512Y-340158D02*
D03*
X544882Y-336221D02*
D03*
X552756Y-335827D02*
D03*
X561024Y-340158D02*
D03*
X568898Y-319009D02*
D03*
X570079Y-309921D02*
D03*
X552756Y-305118D02*
D03*
X544882D02*
D03*
X536221Y-300787D02*
D03*
X530709D02*
D03*
X530315Y-338976D02*
D03*
X513406Y-302902D02*
D03*
X521654Y-336221D02*
D03*
X513386D02*
D03*
X505410Y-336036D02*
D03*
X505512Y-303150D02*
D03*
X455118Y-92520D02*
D03*
X460236Y-87795D02*
D03*
Y-92520D02*
D03*
X454724Y-87795D02*
D03*
X624409Y-31496D02*
D03*
X620079Y-31890D02*
D03*
X615748Y-32283D02*
D03*
X611417Y-33071D02*
D03*
X620866Y-35827D02*
D03*
X611811Y-38189D02*
D03*
X601181Y-23622D02*
D03*
X597244D02*
D03*
Y-29921D02*
D03*
X601181Y-26772D02*
D03*
Y-29921D02*
D03*
X597244Y-26772D02*
D03*
X542913Y-72835D02*
D03*
Y-69291D02*
D03*
Y-65748D02*
D03*
Y-61811D02*
D03*
Y-58268D02*
D03*
X595276Y-79921D02*
D03*
X608405Y-70079D02*
D03*
X618110Y-62205D02*
D03*
X616142Y-47638D02*
D03*
X618898Y-50787D02*
D03*
X613386D02*
D03*
X609547Y-51181D02*
D03*
X606693Y-50787D02*
D03*
X601575Y-53543D02*
D03*
X599213Y-50000D02*
D03*
X544095Y-42126D02*
D03*
X539764D02*
D03*
X534646Y-51968D02*
D03*
X534252Y-48425D02*
D03*
X534646Y-45276D02*
D03*
Y-42126D02*
D03*
X238189Y-107087D02*
D03*
X233071D02*
D03*
X223228Y-107480D02*
D03*
X228346D02*
D03*
X238189Y-138976D02*
D03*
X233209Y-139232D02*
D03*
X228209Y-138721D02*
D03*
X217405Y-138189D02*
D03*
X223209Y-137815D02*
D03*
X214173Y-107087D02*
D03*
X192126Y-111811D02*
D03*
X199193Y-105925D02*
D03*
X204193Y-138257D02*
D03*
X199193Y-138680D02*
D03*
X130245Y-120870D02*
D03*
X133099Y-119984D02*
D03*
X148425Y-104336D02*
D03*
X153150Y-103412D02*
D03*
Y-99691D02*
D03*
X158268Y-107480D02*
D03*
X168110Y-103937D02*
D03*
Y-100132D02*
D03*
X161417Y-95276D02*
D03*
Y-107480D02*
D03*
X178185Y-136811D02*
D03*
Y-133661D02*
D03*
X150627Y-130512D02*
D03*
X150233Y-127362D02*
D03*
X152904Y-124213D02*
D03*
X152398Y-117717D02*
D03*
X156926Y-111614D02*
D03*
X164843Y-114040D02*
D03*
X160075Y-112402D02*
D03*
X168343Y-110827D02*
D03*
X186847Y-135236D02*
D03*
X188028Y-113583D02*
D03*
X189209Y-131339D02*
D03*
Y-117480D02*
D03*
X173461Y-127362D02*
D03*
X165587Y-139961D02*
D03*
X151808Y-137205D02*
D03*
X162241Y-140004D02*
D03*
X106693Y15354D02*
D03*
X107087Y9449D02*
D03*
X111024D02*
D03*
Y15354D02*
D03*
X105512Y-79921D02*
D03*
X109843D02*
D03*
Y-74410D02*
D03*
X105512D02*
D03*
X99606Y-63779D02*
D03*
X107874D02*
D03*
Y-59842D02*
D03*
X99606D02*
D03*
X74616Y-61723D02*
D03*
X56693Y1060D02*
D03*
X39764Y-29528D02*
D03*
Y-25984D02*
D03*
X35731Y-9843D02*
D03*
Y-18898D02*
D03*
X47441Y-27362D02*
D03*
Y-21260D02*
D03*
Y-5709D02*
D03*
Y-11811D02*
D03*
X75394Y-5709D02*
D03*
Y-11811D02*
D03*
X66142D02*
D03*
X61417D02*
D03*
X56693D02*
D03*
Y-16535D02*
D03*
X61417D02*
D03*
X66142D02*
D03*
Y-21260D02*
D03*
X61417D02*
D03*
X52362Y-35531D02*
D03*
X61417Y-35741D02*
D03*
X37402Y-43355D02*
D03*
X38382Y-48355D02*
D03*
X66102Y-64085D02*
D03*
X72795Y-53355D02*
D03*
X86614Y-56299D02*
D03*
X91339Y-35039D02*
D03*
X86614Y-39370D02*
D03*
X88583Y-53937D02*
D03*
X85039D02*
D03*
X88583Y-50787D02*
D03*
X85039D02*
D03*
X88583Y-46457D02*
D03*
X85039Y-46850D02*
D03*
X84252Y-9055D02*
D03*
Y-5906D02*
D03*
Y-2362D02*
D03*
X88257Y-2500D02*
D03*
X93608Y-3379D02*
D03*
X90158Y-7480D02*
D03*
X107832Y-10197D02*
D03*
X97408D02*
D03*
X106693Y-27559D02*
D03*
X105282Y-19291D02*
D03*
X85827Y-16929D02*
D03*
X85853Y-13780D02*
D03*
X78740Y18110D02*
D03*
Y15354D02*
D03*
Y9843D02*
D03*
Y6693D02*
D03*
Y3543D02*
D03*
X110589Y1589D02*
D03*
X108268Y394D02*
D03*
X112598D02*
D03*
X116929Y-21654D02*
D03*
X118898Y-16929D02*
D03*
X366043Y-153937D02*
D03*
X373228Y-162598D02*
D03*
X378346Y-161811D02*
D03*
X388713Y-128731D02*
D03*
X383083Y-128504D02*
D03*
X336221Y-122047D02*
D03*
X333465D02*
D03*
X330315Y-121653D02*
D03*
X335827Y-164173D02*
D03*
X333071D02*
D03*
X329919Y-164008D02*
D03*
X329656Y-142480D02*
D03*
X329722Y-145827D02*
D03*
X347638Y-119882D02*
D03*
X347244Y-113189D02*
D03*
X355035Y-105876D02*
D03*
X390654Y-104510D02*
D03*
X383465Y-103543D02*
D03*
X369685Y-123622D02*
D03*
Y-120866D02*
D03*
Y-118110D02*
D03*
X366929Y-123622D02*
D03*
Y-120866D02*
D03*
X363779Y-123622D02*
D03*
X366929Y-118110D02*
D03*
X363779Y-120866D02*
D03*
Y-118110D02*
D03*
X448425Y-165354D02*
D03*
X451968D02*
D03*
X455512D02*
D03*
X458661D02*
D03*
X442815Y-161747D02*
D03*
Y-165847D02*
D03*
X439561D02*
D03*
X425984Y-109843D02*
D03*
X425630Y-112894D02*
D03*
X416535Y-120768D02*
D03*
X423622Y-115354D02*
D03*
X436811Y-153543D02*
D03*
X418110D02*
D03*
X422835D02*
D03*
X427559D02*
D03*
Y-148819D02*
D03*
X418110D02*
D03*
X422835D02*
D03*
Y-144095D02*
D03*
X418110D02*
D03*
X422835Y-131791D02*
D03*
X427843Y-166966D02*
D03*
X422835Y-166284D02*
D03*
X406693Y-125984D02*
D03*
X408268Y-124409D02*
D03*
Y-122047D02*
D03*
X400984Y-127102D02*
D03*
X415748Y-129609D02*
D03*
X418898Y-129753D02*
D03*
X445276Y-103543D02*
D03*
X444488Y-106299D02*
D03*
X440945Y-105905D02*
D03*
X436221Y-106299D02*
D03*
X434347Y-103743D02*
D03*
X434646Y-100787D02*
D03*
X431496Y-100000D02*
D03*
X422047Y-101969D02*
D03*
X418898Y-100000D02*
D03*
X445669Y-128347D02*
D03*
X449606D02*
D03*
Y-124803D02*
D03*
Y-121653D02*
D03*
X275590Y-199606D02*
D03*
X289370Y-200394D02*
D03*
X274803Y-188583D02*
D03*
X291831Y-197012D02*
D03*
X295669Y-191339D02*
D03*
X292815Y-187106D02*
D03*
X275590Y-184252D02*
D03*
X281890Y-188583D02*
D03*
Y-200771D02*
D03*
X288583Y-195276D02*
D03*
X275503D02*
D03*
X596063Y-239895D02*
D03*
Y-241995D02*
D03*
X321654Y-232677D02*
D03*
X336614Y-286221D02*
D03*
X315945Y-287795D02*
D03*
X315333Y-299430D02*
D03*
X336811Y-299399D02*
D03*
X313386Y-283465D02*
D03*
X308268Y-300000D02*
D03*
X324184Y-302194D02*
D03*
X356693Y-288583D02*
D03*
X355741Y-296063D02*
D03*
X314961Y-293701D02*
D03*
X320472Y-299569D02*
D03*
X325776Y-293701D02*
D03*
X320472Y-287865D02*
D03*
X345161Y-292913D02*
D03*
X333465D02*
D03*
X339370Y-286162D02*
D03*
Y-298819D02*
D03*
X329134Y-228740D02*
D03*
X341274Y-242913D02*
D03*
X340786Y-235827D02*
D03*
X312322Y-236221D02*
D03*
X309782Y-243307D02*
D03*
X334842Y-247244D02*
D03*
X319685Y-245276D02*
D03*
X333714Y-239764D02*
D03*
X325590Y-246324D02*
D03*
Y-232344D02*
D03*
X317009Y-239764D02*
D03*
X390896Y-249065D02*
D03*
X386615Y-249113D02*
D03*
X400000Y-219291D02*
D03*
X398472Y-235531D02*
D03*
X378937Y-249803D02*
D03*
X367654Y-236614D02*
D03*
X373093Y-232972D02*
D03*
X375197Y-221260D02*
D03*
X382776Y-221555D02*
D03*
X368232Y-217717D02*
D03*
X390158D02*
D03*
X415623Y-358391D02*
D03*
X414772Y-353273D02*
D03*
X449150Y-355832D02*
D03*
X460678Y-359179D02*
D03*
X460900Y-354061D02*
D03*
X493234Y-356620D02*
D03*
X533931Y-356296D02*
D03*
X499525Y-358855D02*
D03*
X499302Y-353737D02*
D03*
X579072Y-356690D02*
D03*
X561330Y-356099D02*
D03*
X543698Y-358659D02*
D03*
X543718Y-353540D02*
D03*
X626987Y-228346D02*
D03*
X605512Y-261024D02*
D03*
Y-256693D02*
D03*
X622835Y-244094D02*
D03*
Y-235433D02*
D03*
X618504Y-252362D02*
D03*
X622101Y-250000D02*
D03*
X622803Y-241006D02*
D03*
X605317Y-252756D02*
D03*
X610236Y-300000D02*
D03*
X619148Y-302756D02*
D03*
X622221Y-313481D02*
D03*
X622753Y-353307D02*
D03*
X622677Y-333307D02*
D03*
X623228Y-343307D02*
D03*
X598583Y-353307D02*
D03*
X598819Y-343307D02*
D03*
X598959Y-333307D02*
D03*
X598898Y-313307D02*
D03*
X393701Y-168898D02*
D03*
X378594Y-166966D02*
D03*
X348031Y-165748D02*
D03*
X342808Y-166966D02*
D03*
X337795Y-181102D02*
D03*
X334252Y-180315D02*
D03*
X310236Y-165748D02*
D03*
X309055Y-195669D02*
D03*
X314675Y-198819D02*
D03*
X319291Y-196850D02*
D03*
X322835Y-196063D02*
D03*
X373730Y-202888D02*
D03*
X375698Y-197700D02*
D03*
X383572Y-206205D02*
D03*
X385541Y-202460D02*
D03*
X155427Y-33907D02*
D03*
X155328Y-26033D02*
D03*
X122539D02*
D03*
X142126Y-348031D02*
D03*
X141587Y-352161D02*
D03*
X377658Y-346144D02*
D03*
X256890Y-374655D02*
D03*
X380807Y-346144D02*
D03*
X253655Y-374421D02*
D03*
X269502Y-374291D02*
D03*
X273425Y-374655D02*
D03*
X374114Y-328034D02*
D03*
X371359D02*
D03*
X22047Y-335433D02*
D03*
X2097Y-349213D02*
D03*
X27067Y-282677D02*
D03*
X5584Y-238905D02*
D03*
X35120Y-228937D02*
D03*
X10630Y-197638D02*
D03*
X19976Y-200787D02*
D03*
Y-220472D02*
D03*
X22441Y-167323D02*
D03*
X19685D02*
D03*
X16929D02*
D03*
X23228Y-147244D02*
D03*
X20079D02*
D03*
X17323D02*
D03*
X27165Y-179134D02*
D03*
X-7874Y-188976D02*
D03*
X364173Y-332283D02*
D03*
X370079D02*
D03*
X377658Y-327985D02*
D03*
X369703Y-326432D02*
D03*
X344882Y-328346D02*
D03*
X348425Y-328740D02*
D03*
X381989Y-348458D02*
D03*
X376870D02*
D03*
X374902D02*
D03*
X370472Y-348425D02*
D03*
X368294Y-348913D02*
D03*
X363878Y-348458D02*
D03*
X361910D02*
D03*
X356792D02*
D03*
X349705Y-348064D02*
D03*
X354823Y-348851D02*
D03*
X156693Y-18110D02*
D03*
X203689Y-248906D02*
D03*
X203937Y-242913D02*
D03*
X451674Y-283940D02*
D03*
X381989Y-331971D02*
D03*
X370178Y-315042D02*
D03*
X342618Y-315081D02*
D03*
X451674Y-234727D02*
D03*
X258702Y-264859D02*
D03*
X445768Y-254381D02*
D03*
X359874Y-183841D02*
D03*
X263322Y-246466D02*
D03*
X340847Y-179215D02*
D03*
X451674Y-244570D02*
D03*
X258760Y-256529D02*
D03*
X445768Y-264255D02*
D03*
X350327Y-183546D02*
D03*
X263622Y-236666D02*
D03*
X352461Y-315042D02*
D03*
X330705Y-179215D02*
D03*
X263122Y-285766D02*
D03*
X364272Y-315042D02*
D03*
X343012Y-332365D02*
D03*
X451674Y-254381D02*
D03*
X350327Y-179215D02*
D03*
X258622Y-246466D02*
D03*
X322933Y-332365D02*
D03*
X445768Y-275261D02*
D03*
X340256Y-183841D02*
D03*
X263580Y-226943D02*
D03*
X445768Y-224885D02*
D03*
X320473Y-179117D02*
D03*
X263322Y-276066D02*
D03*
X352106Y-332482D02*
D03*
X451674Y-264255D02*
D03*
X259022Y-236566D02*
D03*
X322540Y-315042D02*
D03*
X445768Y-283940D02*
D03*
X331091Y-184050D02*
D03*
X258622Y-285766D02*
D03*
X376477Y-315042D02*
D03*
X357973Y-315042D02*
D03*
X445768Y-234727D02*
D03*
X379496Y-183803D02*
D03*
Y-179215D02*
D03*
X262922Y-265040D02*
D03*
X332776Y-332365D02*
D03*
X451674Y-275261D02*
D03*
X369981Y-179215D02*
D03*
X258922Y-226766D02*
D03*
X451674Y-224885D02*
D03*
X360138Y-179215D02*
D03*
X258622Y-276066D02*
D03*
X381595Y-315042D02*
D03*
X445768Y-244570D02*
D03*
X369685Y-183841D02*
D03*
X263681Y-256529D02*
D03*
X332382Y-315042D02*
D03*
X19976Y-252953D02*
D03*
Y-272638D02*
D03*
Y-326772D02*
D03*
Y-307087D02*
D03*
X100729Y-123872D02*
D03*
X163071Y-390730D02*
D03*
X259285Y-390247D02*
D03*
X267204Y-390009D02*
D03*
X216162Y-390947D02*
D03*
X235144Y-390416D02*
D03*
X251456Y-390009D02*
D03*
X226063Y-390722D02*
D03*
X281201Y-390009D02*
D03*
X174941Y-390600D02*
D03*
X202441D02*
D03*
X-23622Y-187992D02*
D03*
X26772Y-348819D02*
D03*
X-1181Y-352831D02*
D03*
X4331Y-344488D02*
D03*
X12598Y-349213D02*
D03*
X35039Y-289961D02*
D03*
Y-285827D02*
D03*
X27067Y-298727D02*
D03*
X10630Y-292126D02*
D03*
X14173Y-294320D02*
D03*
X288Y-234968D02*
D03*
X10007D02*
D03*
X19685Y-239370D02*
D03*
X14665Y-237402D02*
D03*
X36220Y-235039D02*
D03*
X36614Y-232677D02*
D03*
X35039Y-237402D02*
D03*
X30709Y-190411D02*
D03*
X33071Y-185755D02*
D03*
X35827D02*
D03*
X13780Y-190551D02*
D03*
X9843Y-185755D02*
D03*
X19682Y-192520D02*
D03*
X-10630Y-178347D02*
D03*
X198392Y-366842D02*
D03*
X196701Y-370523D02*
D03*
X394193Y-197670D02*
D03*
X380363Y-196740D02*
D03*
X157480Y-361811D02*
D03*
X153543Y-358661D02*
D03*
Y-361811D02*
D03*
X155512D02*
D03*
Y-358661D02*
D03*
X157480D02*
D03*
X157087Y-41732D02*
D03*
X230165Y-235119D02*
D03*
X246162Y-293733D02*
D03*
X230406Y-251861D02*
D03*
X230251Y-232266D02*
D03*
X204331Y-232677D02*
D03*
X203937Y-235827D02*
D03*
Y-238189D02*
D03*
X203805Y-240564D02*
D03*
X203805Y-252182D02*
D03*
X203937Y-254724D02*
D03*
X154724Y-389616D02*
D03*
X156693D02*
D03*
X158661D02*
D03*
X154724Y-386466D02*
D03*
X156693D02*
D03*
X158661D02*
D03*
X280414Y-293782D02*
D03*
X245965Y-264497D02*
D03*
Y-254655D02*
D03*
X432835Y-291755D02*
D03*
X472047Y-221260D02*
D03*
X430020Y-218979D02*
D03*
X472047Y-223228D02*
D03*
X430020Y-220948D02*
D03*
Y-222916D02*
D03*
X472047Y-219291D02*
D03*
X430020Y-217010D02*
D03*
X121457Y-57529D02*
D03*
X280382Y-274277D02*
D03*
X337774Y-196489D02*
D03*
X274719Y-244928D02*
D03*
X276755Y-246539D02*
D03*
X280414Y-283478D02*
D03*
Y-287478D02*
D03*
X331220Y-196266D02*
D03*
X341774Y-196326D02*
D03*
X326705Y-179059D02*
D03*
X324705Y-184678D02*
D03*
X463453Y-247883D02*
D03*
X464472Y-245540D02*
D03*
X327658Y-184678D02*
D03*
X36614Y18701D02*
D03*
X244028Y-262466D02*
D03*
Y-258497D02*
D03*
X243996Y-252592D02*
D03*
X245965Y-250655D02*
D03*
X243996Y-248655D02*
D03*
X245965Y-260497D02*
D03*
X-23622Y-342520D02*
D03*
X100729Y-119871D02*
D03*
X-23622Y-229331D02*
D03*
Y-233268D02*
D03*
Y-237205D02*
D03*
Y-241142D02*
D03*
Y-282480D02*
D03*
Y-286417D02*
D03*
Y-290354D02*
D03*
Y-294291D02*
D03*
Y-335630D02*
D03*
Y-339567D02*
D03*
Y-66929D02*
D03*
Y-62992D02*
D03*
Y-60039D02*
D03*
Y-102362D02*
D03*
Y-106299D02*
D03*
Y-110236D02*
D03*
Y-184055D02*
D03*
Y-177165D02*
D03*
X472047Y-217323D02*
D03*
X190354Y-377411D02*
D03*
X178543D02*
D03*
X362598Y-197244D02*
D03*
X36762Y11811D02*
D03*
X36614Y4921D02*
D03*
Y-1969D02*
D03*
X389567Y-196440D02*
D03*
X432579Y-283251D02*
D03*
Y-286400D02*
D03*
X432720Y-289358D02*
D03*
D251*
X127392Y-94557D02*
D03*
X365581Y7806D02*
D03*
Y-94557D02*
D03*
X127392Y7806D02*
D03*
X479695Y-331073D02*
D03*
X582058Y-92884D02*
D03*
X479695D02*
D03*
X582058Y-331073D02*
D03*
D252*
X218189Y-404100D02*
D03*
D253*
X564889Y-280519D02*
D03*
Y-282487D02*
D03*
Y-278550D02*
D03*
Y-276582D02*
D03*
X570676D02*
D03*
Y-278550D02*
D03*
Y-280519D02*
D03*
Y-282487D02*
D03*
X536772Y-273701D02*
D03*
Y-271732D02*
D03*
Y-275669D02*
D03*
Y-277638D02*
D03*
X530984D02*
D03*
Y-275669D02*
D03*
Y-273701D02*
D03*
Y-271732D02*
D03*
D254*
X532266Y-282481D02*
D03*
X536203D02*
D03*
X568963Y-272841D02*
D03*
X565026D02*
D03*
X558727Y-275597D02*
D03*
X554790D02*
D03*
D255*
X542126Y-277953D02*
D03*
Y-281890D02*
D03*
D256*
X111024Y-21752D02*
D03*
Y-25492D02*
D03*
D257*
X287835Y-273622D02*
D03*
X293268D02*
D03*
D258*
X400984Y-129921D02*
D03*
X403937D02*
D03*
D259*
X412205Y-129528D02*
D03*
X408268D02*
D03*
D260*
X431943Y-132677D02*
D03*
X427900D02*
D03*
D261*
X423917Y-137992D02*
D03*
X427658D02*
D03*
X56595Y-27362D02*
D03*
X60335D02*
D03*
D262*
X56824Y-31594D02*
D03*
Y-35531D02*
D03*
D263*
X378083Y-153937D02*
D03*
Y-157087D02*
D03*
X373083Y-153937D02*
D03*
Y-157087D02*
D03*
X603357Y-83008D02*
D03*
Y-79858D02*
D03*
X598425Y-83071D02*
D03*
Y-79921D02*
D03*
X158008Y-118602D02*
D03*
Y-115453D02*
D03*
X164012Y-128150D02*
D03*
Y-131299D02*
D03*
D264*
X432237Y-199705D02*
D03*
Y-204232D02*
D03*
D265*
X26083Y16339D02*
D03*
X31398D02*
D03*
X26083Y9449D02*
D03*
X31398D02*
D03*
X26083Y2559D02*
D03*
X31398D02*
D03*
X26083Y-4331D02*
D03*
X31398D02*
D03*
X199114Y-130709D02*
D03*
X204035D02*
D03*
D266*
X561024Y-330315D02*
D03*
X553150D02*
D03*
X529282Y-328837D02*
D03*
X537156D02*
D03*
X562205Y-309842D02*
D03*
X570079D02*
D03*
X529282Y-312272D02*
D03*
X537156D02*
D03*
X125984Y-36220D02*
D03*
X118110D02*
D03*
X121467Y-74575D02*
D03*
X129341D02*
D03*
X144096Y-71072D02*
D03*
X151970D02*
D03*
D267*
X148632Y-49655D02*
D03*
Y-41781D02*
D03*
D268*
X612781Y-302756D02*
D03*
X615762D02*
D03*
X152904Y-124213D02*
D03*
X149924D02*
D03*
D269*
X604252Y-242991D02*
D03*
X601181D02*
D03*
X604252Y-239054D02*
D03*
X601181D02*
D03*
D270*
X172939Y-124276D02*
D03*
Y-120812D02*
D03*
X59016Y-54241D02*
D03*
Y-57706D02*
D03*
X168441Y-115295D02*
D03*
Y-118760D02*
D03*
X273441Y-382293D02*
D03*
Y-378907D02*
D03*
X206441D02*
D03*
Y-382293D02*
D03*
X210441D02*
D03*
Y-378907D02*
D03*
X218341D02*
D03*
Y-382293D02*
D03*
X222641D02*
D03*
Y-378907D02*
D03*
X237941Y-382293D02*
D03*
Y-378907D02*
D03*
X241941Y-382293D02*
D03*
Y-378907D02*
D03*
X253441Y-382293D02*
D03*
Y-378907D02*
D03*
X256941D02*
D03*
Y-382293D02*
D03*
X269441D02*
D03*
Y-378907D02*
D03*
D271*
X388713Y-135039D02*
D03*
X383201D02*
D03*
X613779Y-64961D02*
D03*
X608268D02*
D03*
D272*
X609291Y-59842D02*
D03*
X612756D02*
D03*
X384532Y-141339D02*
D03*
X387996D02*
D03*
D273*
X228150Y-132677D02*
D03*
X223031D02*
D03*
X238386Y-131890D02*
D03*
X233268D02*
D03*
D274*
X46850Y-154331D02*
Y-148819D01*
X56980Y-162491D02*
X58268Y-163779D01*
X51468Y-162491D02*
X56980D01*
X46850Y-157874D02*
X51468Y-162491D01*
X46850Y-157874D02*
Y-154331D01*
D275*
X156644Y-388287D02*
D03*
M02*
